(kicad_sch
	(version 20250114)
	(generator "eeschema")
	(generator_version "9.0")
	(paper "A3")
	(title_block
		(title "OCuLink to 10GbE adapter")
		(date "2026-02-23")
		(rev "1.1.0")
		(company "Antmicro Ltd")
		(comment 1 "www.antmicro.com")
	)
	(text "10GbE Port 1"
		(exclude_from_sim no)
		(at 215.9 173.99 0)
		(effects
			(font
				(size 2.54 2.54)
				(thickness 0.508)
				(bold yes)
			)
		)
	)
	(text "10GbE Port 0"
		(exclude_from_sim no)
		(at 215.9 38.1 0)
		(effects
			(font
				(size 2.54 2.54)
				(thickness 0.508)
				(bold yes)
			)
		)
	)
	(junction
		(at 154.94 233.68)
		(diameter 0)
		(color 0 0 0 0)
	)
	(junction
		(at 228.6 215.9)
		(diameter 0)
		(color 0 0 0 0)
	)
	(junction
		(at 92.71 97.79)
		(diameter 0)
		(color 0 0 0 0)
	)
	(junction
		(at 194.31 97.79)
		(diameter 0)
		(color 0 0 0 0)
	)
	(junction
		(at 243.84 220.98)
		(diameter 0)
		(color 0 0 0 0)
	)
	(junction
		(at 176.53 233.68)
		(diameter 0)
		(color 0 0 0 0)
	)
	(junction
		(at 233.68 241.3)
		(diameter 0)
		(color 0 0 0 0)
	)
	(junction
		(at 243.84 105.41)
		(diameter 0)
		(color 0 0 0 0)
	)
	(junction
		(at 201.93 231.14)
		(diameter 0)
		(color 0 0 0 0)
	)
	(junction
		(at 167.64 97.79)
		(diameter 0)
		(color 0 0 0 0)
	)
	(junction
		(at 185.42 233.68)
		(diameter 0)
		(color 0 0 0 0)
	)
	(junction
		(at 154.94 97.79)
		(diameter 0)
		(color 0 0 0 0)
	)
	(junction
		(at 201.93 97.79)
		(diameter 0)
		(color 0 0 0 0)
	)
	(junction
		(at 201.93 95.25)
		(diameter 0)
		(color 0 0 0 0)
	)
	(junction
		(at 167.64 233.68)
		(diameter 0)
		(color 0 0 0 0)
	)
	(junction
		(at 228.6 105.41)
		(diameter 0)
		(color 0 0 0 0)
	)
	(junction
		(at 201.93 233.68)
		(diameter 0)
		(color 0 0 0 0)
	)
	(junction
		(at 243.84 241.3)
		(diameter 0)
		(color 0 0 0 0)
	)
	(junction
		(at 254 92.71)
		(diameter 0)
		(color 0 0 0 0)
	)
	(junction
		(at 71.12 97.79)
		(diameter 0)
		(color 0 0 0 0)
	)
	(junction
		(at 233.68 82.55)
		(diameter 0)
		(color 0 0 0 0)
	)
	(junction
		(at 201.93 228.6)
		(diameter 0)
		(color 0 0 0 0)
	)
	(junction
		(at 59.69 97.79)
		(diameter 0)
		(color 0 0 0 0)
	)
	(junction
		(at 194.31 233.68)
		(diameter 0)
		(color 0 0 0 0)
	)
	(junction
		(at 228.6 241.3)
		(diameter 0)
		(color 0 0 0 0)
	)
	(junction
		(at 243.84 85.09)
		(diameter 0)
		(color 0 0 0 0)
	)
	(junction
		(at 368.3 121.92)
		(diameter 0)
		(color 0 0 0 0)
	)
	(junction
		(at 86.36 97.79)
		(diameter 0)
		(color 0 0 0 0)
	)
	(junction
		(at 228.6 80.01)
		(diameter 0)
		(color 0 0 0 0)
	)
	(junction
		(at 201.93 92.71)
		(diameter 0)
		(color 0 0 0 0)
	)
	(junction
		(at 254 228.6)
		(diameter 0)
		(color 0 0 0 0)
	)
	(junction
		(at 95.25 97.79)
		(diameter 0)
		(color 0 0 0 0)
	)
	(junction
		(at 233.68 105.41)
		(diameter 0)
		(color 0 0 0 0)
	)
	(junction
		(at 176.53 97.79)
		(diameter 0)
		(color 0 0 0 0)
	)
	(junction
		(at 233.68 218.44)
		(diameter 0)
		(color 0 0 0 0)
	)
	(junction
		(at 185.42 97.79)
		(diameter 0)
		(color 0 0 0 0)
	)
	(bus_entry
		(at 181.61 67.31)
		(size 2.54 -2.54)
		(stroke
			(width 0)
			(type default)
		)
	)
	(bus_entry
		(at 181.61 80.01)
		(size 2.54 -2.54)
		(stroke
			(width 0)
			(type default)
		)
	)
	(bus_entry
		(at 181.61 64.77)
		(size 2.54 -2.54)
		(stroke
			(width 0)
			(type default)
		)
	)
	(bus_entry
		(at 181.61 77.47)
		(size 2.54 -2.54)
		(stroke
			(width 0)
			(type default)
		)
	)
	(bus_entry
		(at 181.61 205.74)
		(size 2.54 -2.54)
		(stroke
			(width 0)
			(type default)
		)
	)
	(bus_entry
		(at 181.61 69.85)
		(size 2.54 -2.54)
		(stroke
			(width 0)
			(type default)
		)
	)
	(bus_entry
		(at 181.61 72.39)
		(size 2.54 -2.54)
		(stroke
			(width 0)
			(type default)
		)
	)
	(bus_entry
		(at 181.61 215.9)
		(size 2.54 -2.54)
		(stroke
			(width 0)
			(type default)
		)
	)
	(bus_entry
		(at 181.61 203.2)
		(size 2.54 -2.54)
		(stroke
			(width 0)
			(type default)
		)
	)
	(bus_entry
		(at 181.61 218.44)
		(size 2.54 -2.54)
		(stroke
			(width 0)
			(type default)
		)
	)
	(bus_entry
		(at 181.61 82.55)
		(size 2.54 -2.54)
		(stroke
			(width 0)
			(type default)
		)
	)
	(bus_entry
		(at 181.61 74.93)
		(size 2.54 -2.54)
		(stroke
			(width 0)
			(type default)
		)
	)
	(bus_entry
		(at 181.61 208.28)
		(size 2.54 -2.54)
		(stroke
			(width 0)
			(type default)
		)
	)
	(bus_entry
		(at 181.61 200.66)
		(size 2.54 -2.54)
		(stroke
			(width 0)
			(type default)
		)
	)
	(bus_entry
		(at 181.61 210.82)
		(size 2.54 -2.54)
		(stroke
			(width 0)
			(type default)
		)
	)
	(bus_entry
		(at 181.61 213.36)
		(size 2.54 -2.54)
		(stroke
			(width 0)
			(type default)
		)
	)
	(wire
		(pts
			(xy 243.84 105.41) (xy 233.68 105.41)
		)
		(stroke
			(width 0)
			(type default)
		)
	)
	(bus
		(pts
			(xy 181.61 218.44) (xy 181.61 220.98)
		)
		(stroke
			(width 0)
			(type default)
		)
	)
	(wire
		(pts
			(xy 254 228.6) (xy 259.08 228.6)
		)
		(stroke
			(width 0)
			(type default)
		)
	)
	(wire
		(pts
			(xy 106.68 97.79) (xy 106.68 96.52)
		)
		(stroke
			(width 0)
			(type default)
		)
	)
	(wire
		(pts
			(xy 154.94 97.79) (xy 167.64 97.79)
		)
		(stroke
			(width 0)
			(type default)
		)
	)
	(wire
		(pts
			(xy 228.6 105.41) (xy 233.68 105.41)
		)
		(stroke
			(width 0)
			(type default)
		)
	)
	(bus
		(pts
			(xy 181.61 72.39) (xy 181.61 74.93)
		)
		(stroke
			(width 0)
			(type default)
		)
	)
	(wire
		(pts
			(xy 226.06 218.44) (xy 233.68 218.44)
		)
		(stroke
			(width 0)
			(type default)
		)
	)
	(wire
		(pts
			(xy 185.42 97.79) (xy 185.42 100.33)
		)
		(stroke
			(width 0)
			(type default)
		)
	)
	(wire
		(pts
			(xy 204.47 64.77) (xy 184.15 64.77)
		)
		(stroke
			(width 0)
			(type default)
		)
	)
	(wire
		(pts
			(xy 142.24 233.68) (xy 147.32 233.68)
		)
		(stroke
			(width 0)
			(type default)
		)
	)
	(wire
		(pts
			(xy 95.25 105.41) (xy 95.25 107.95)
		)
		(stroke
			(width 0)
			(type default)
		)
	)
	(wire
		(pts
			(xy 167.64 233.68) (xy 176.53 233.68)
		)
		(stroke
			(width 0)
			(type default)
		)
	)
	(wire
		(pts
			(xy 194.31 233.68) (xy 194.31 236.22)
		)
		(stroke
			(width 0)
			(type default)
		)
	)
	(bus
		(pts
			(xy 179.07 87.63) (xy 181.61 85.09)
		)
		(stroke
			(width 0)
			(type default)
		)
	)
	(wire
		(pts
			(xy 106.68 97.79) (xy 95.25 97.79)
		)
		(stroke
			(width 0)
			(type default)
		)
	)
	(bus
		(pts
			(xy 179.07 223.52) (xy 181.61 220.98)
		)
		(stroke
			(width 0)
			(type default)
		)
	)
	(bus
		(pts
			(xy 181.61 67.31) (xy 181.61 69.85)
		)
		(stroke
			(width 0)
			(type default)
		)
	)
	(wire
		(pts
			(xy 204.47 213.36) (xy 184.15 213.36)
		)
		(stroke
			(width 0)
			(type default)
		)
	)
	(bus
		(pts
			(xy 181.61 74.93) (xy 181.61 77.47)
		)
		(stroke
			(width 0)
			(type default)
		)
	)
	(wire
		(pts
			(xy 204.47 77.47) (xy 184.15 77.47)
		)
		(stroke
			(width 0)
			(type default)
		)
	)
	(wire
		(pts
			(xy 264.16 82.55) (xy 271.78 82.55)
		)
		(stroke
			(width 0)
			(type default)
		)
	)
	(bus
		(pts
			(xy 181.61 64.77) (xy 181.61 67.31)
		)
		(stroke
			(width 0)
			(type default)
		)
	)
	(bus
		(pts
			(xy 181.61 200.66) (xy 181.61 203.2)
		)
		(stroke
			(width 0)
			(type default)
		)
	)
	(wire
		(pts
			(xy 142.24 95.25) (xy 142.24 97.79)
		)
		(stroke
			(width 0)
			(type default)
		)
	)
	(wire
		(pts
			(xy 167.64 105.41) (xy 167.64 107.95)
		)
		(stroke
			(width 0)
			(type default)
		)
	)
	(wire
		(pts
			(xy 243.84 220.98) (xy 259.08 220.98)
		)
		(stroke
			(width 0)
			(type default)
		)
	)
	(wire
		(pts
			(xy 368.3 121.92) (xy 370.84 121.92)
		)
		(stroke
			(width 0)
			(type default)
		)
	)
	(wire
		(pts
			(xy 142.24 97.79) (xy 147.32 97.79)
		)
		(stroke
			(width 0)
			(type default)
		)
	)
	(wire
		(pts
			(xy 226.06 226.06) (xy 228.6 226.06)
		)
		(stroke
			(width 0)
			(type default)
		)
	)
	(wire
		(pts
			(xy 233.68 238.76) (xy 233.68 241.3)
		)
		(stroke
			(width 0)
			(type default)
		)
	)
	(wire
		(pts
			(xy 264.16 85.09) (xy 271.78 85.09)
		)
		(stroke
			(width 0)
			(type default)
		)
	)
	(wire
		(pts
			(xy 154.94 97.79) (xy 154.94 100.33)
		)
		(stroke
			(width 0)
			(type default)
		)
	)
	(wire
		(pts
			(xy 154.94 233.68) (xy 154.94 236.22)
		)
		(stroke
			(width 0)
			(type default)
		)
	)
	(wire
		(pts
			(xy 167.64 236.22) (xy 167.64 233.68)
		)
		(stroke
			(width 0)
			(type default)
		)
	)
	(wire
		(pts
			(xy 226.06 215.9) (xy 228.6 215.9)
		)
		(stroke
			(width 0)
			(type default)
		)
	)
	(wire
		(pts
			(xy 228.6 215.9) (xy 228.6 213.36)
		)
		(stroke
			(width 0)
			(type default)
		)
	)
	(wire
		(pts
			(xy 233.68 218.44) (xy 233.68 233.68)
		)
		(stroke
			(width 0)
			(type default)
		)
	)
	(wire
		(pts
			(xy 226.06 92.71) (xy 254 92.71)
		)
		(stroke
			(width 0)
			(type default)
		)
	)
	(wire
		(pts
			(xy 243.84 102.87) (xy 243.84 105.41)
		)
		(stroke
			(width 0)
			(type default)
		)
	)
	(wire
		(pts
			(xy 59.69 97.79) (xy 71.12 97.79)
		)
		(stroke
			(width 0)
			(type default)
		)
	)
	(wire
		(pts
			(xy 81.28 97.79) (xy 86.36 97.79)
		)
		(stroke
			(width 0)
			(type default)
		)
	)
	(wire
		(pts
			(xy 71.12 97.79) (xy 71.12 100.33)
		)
		(stroke
			(width 0)
			(type default)
		)
	)
	(wire
		(pts
			(xy 59.69 97.79) (xy 59.69 100.33)
		)
		(stroke
			(width 0)
			(type default)
		)
	)
	(wire
		(pts
			(xy 204.47 208.28) (xy 184.15 208.28)
		)
		(stroke
			(width 0)
			(type default)
		)
	)
	(wire
		(pts
			(xy 201.93 233.68) (xy 204.47 233.68)
		)
		(stroke
			(width 0)
			(type default)
		)
	)
	(wire
		(pts
			(xy 264.16 228.6) (xy 271.78 228.6)
		)
		(stroke
			(width 0)
			(type default)
		)
	)
	(wire
		(pts
			(xy 86.36 97.79) (xy 92.71 97.79)
		)
		(stroke
			(width 0)
			(type default)
		)
	)
	(wire
		(pts
			(xy 226.06 233.68) (xy 228.6 233.68)
		)
		(stroke
			(width 0)
			(type default)
		)
	)
	(wire
		(pts
			(xy 92.71 97.79) (xy 95.25 97.79)
		)
		(stroke
			(width 0)
			(type default)
		)
	)
	(wire
		(pts
			(xy 185.42 233.68) (xy 194.31 233.68)
		)
		(stroke
			(width 0)
			(type default)
		)
	)
	(wire
		(pts
			(xy 233.68 82.55) (xy 259.08 82.55)
		)
		(stroke
			(width 0)
			(type default)
		)
	)
	(wire
		(pts
			(xy 226.06 97.79) (xy 228.6 97.79)
		)
		(stroke
			(width 0)
			(type default)
		)
	)
	(wire
		(pts
			(xy 201.93 231.14) (xy 201.93 228.6)
		)
		(stroke
			(width 0)
			(type default)
		)
	)
	(wire
		(pts
			(xy 243.84 241.3) (xy 233.68 241.3)
		)
		(stroke
			(width 0)
			(type default)
		)
	)
	(wire
		(pts
			(xy 86.36 97.79) (xy 86.36 100.33)
		)
		(stroke
			(width 0)
			(type default)
		)
	)
	(wire
		(pts
			(xy 243.84 238.76) (xy 243.84 241.3)
		)
		(stroke
			(width 0)
			(type default)
		)
	)
	(wire
		(pts
			(xy 254 241.3) (xy 243.84 241.3)
		)
		(stroke
			(width 0)
			(type default)
		)
	)
	(wire
		(pts
			(xy 204.47 90.17) (xy 201.93 90.17)
		)
		(stroke
			(width 0)
			(type default)
		)
	)
	(bus
		(pts
			(xy 181.61 80.01) (xy 181.61 82.55)
		)
		(stroke
			(width 0)
			(type default)
		)
	)
	(wire
		(pts
			(xy 204.47 198.12) (xy 184.15 198.12)
		)
		(stroke
			(width 0)
			(type default)
		)
	)
	(wire
		(pts
			(xy 201.93 228.6) (xy 204.47 228.6)
		)
		(stroke
			(width 0)
			(type default)
		)
	)
	(wire
		(pts
			(xy 204.47 203.2) (xy 184.15 203.2)
		)
		(stroke
			(width 0)
			(type default)
		)
	)
	(wire
		(pts
			(xy 204.47 205.74) (xy 184.15 205.74)
		)
		(stroke
			(width 0)
			(type default)
		)
	)
	(wire
		(pts
			(xy 154.94 233.68) (xy 167.64 233.68)
		)
		(stroke
			(width 0)
			(type default)
		)
	)
	(bus
		(pts
			(xy 181.61 69.85) (xy 181.61 72.39)
		)
		(stroke
			(width 0)
			(type default)
		)
	)
	(wire
		(pts
			(xy 233.68 102.87) (xy 233.68 105.41)
		)
		(stroke
			(width 0)
			(type default)
		)
	)
	(wire
		(pts
			(xy 204.47 215.9) (xy 184.15 215.9)
		)
		(stroke
			(width 0)
			(type default)
		)
	)
	(wire
		(pts
			(xy 254 92.71) (xy 259.08 92.71)
		)
		(stroke
			(width 0)
			(type default)
		)
	)
	(wire
		(pts
			(xy 152.4 233.68) (xy 154.94 233.68)
		)
		(stroke
			(width 0)
			(type default)
		)
	)
	(wire
		(pts
			(xy 204.47 67.31) (xy 184.15 67.31)
		)
		(stroke
			(width 0)
			(type default)
		)
	)
	(wire
		(pts
			(xy 185.42 233.68) (xy 185.42 236.22)
		)
		(stroke
			(width 0)
			(type default)
		)
	)
	(wire
		(pts
			(xy 185.42 105.41) (xy 185.42 107.95)
		)
		(stroke
			(width 0)
			(type default)
		)
	)
	(wire
		(pts
			(xy 176.53 241.3) (xy 176.53 243.84)
		)
		(stroke
			(width 0)
			(type default)
		)
	)
	(wire
		(pts
			(xy 368.3 114.3) (xy 368.3 121.92)
		)
		(stroke
			(width 0)
			(type default)
		)
	)
	(wire
		(pts
			(xy 201.93 228.6) (xy 201.93 226.06)
		)
		(stroke
			(width 0)
			(type default)
		)
	)
	(wire
		(pts
			(xy 185.42 241.3) (xy 185.42 243.84)
		)
		(stroke
			(width 0)
			(type default)
		)
	)
	(wire
		(pts
			(xy 243.84 220.98) (xy 243.84 233.68)
		)
		(stroke
			(width 0)
			(type default)
		)
	)
	(wire
		(pts
			(xy 264.16 92.71) (xy 271.78 92.71)
		)
		(stroke
			(width 0)
			(type default)
		)
	)
	(wire
		(pts
			(xy 264.16 220.98) (xy 271.78 220.98)
		)
		(stroke
			(width 0)
			(type default)
		)
	)
	(wire
		(pts
			(xy 204.47 200.66) (xy 184.15 200.66)
		)
		(stroke
			(width 0)
			(type default)
		)
	)
	(wire
		(pts
			(xy 71.12 105.41) (xy 71.12 107.95)
		)
		(stroke
			(width 0)
			(type default)
		)
	)
	(wire
		(pts
			(xy 254 228.6) (xy 254 233.68)
		)
		(stroke
			(width 0)
			(type default)
		)
	)
	(wire
		(pts
			(xy 176.53 105.41) (xy 176.53 107.95)
		)
		(stroke
			(width 0)
			(type default)
		)
	)
	(wire
		(pts
			(xy 228.6 241.3) (xy 228.6 243.84)
		)
		(stroke
			(width 0)
			(type default)
		)
	)
	(wire
		(pts
			(xy 226.06 82.55) (xy 233.68 82.55)
		)
		(stroke
			(width 0)
			(type default)
		)
	)
	(wire
		(pts
			(xy 228.6 241.3) (xy 233.68 241.3)
		)
		(stroke
			(width 0)
			(type default)
		)
	)
	(wire
		(pts
			(xy 204.47 69.85) (xy 184.15 69.85)
		)
		(stroke
			(width 0)
			(type default)
		)
	)
	(bus
		(pts
			(xy 181.61 77.47) (xy 181.61 80.01)
		)
		(stroke
			(width 0)
			(type default)
		)
	)
	(bus
		(pts
			(xy 181.61 213.36) (xy 181.61 215.9)
		)
		(stroke
			(width 0)
			(type default)
		)
	)
	(bus
		(pts
			(xy 179.07 87.63) (xy 176.53 87.63)
		)
		(stroke
			(width 0)
			(type default)
		)
	)
	(wire
		(pts
			(xy 92.71 95.25) (xy 92.71 97.79)
		)
		(stroke
			(width 0)
			(type default)
		)
	)
	(wire
		(pts
			(xy 204.47 80.01) (xy 184.15 80.01)
		)
		(stroke
			(width 0)
			(type default)
		)
	)
	(wire
		(pts
			(xy 201.93 231.14) (xy 204.47 231.14)
		)
		(stroke
			(width 0)
			(type default)
		)
	)
	(wire
		(pts
			(xy 228.6 215.9) (xy 228.6 226.06)
		)
		(stroke
			(width 0)
			(type default)
		)
	)
	(wire
		(pts
			(xy 59.69 105.41) (xy 59.69 107.95)
		)
		(stroke
			(width 0)
			(type default)
		)
	)
	(wire
		(pts
			(xy 201.93 97.79) (xy 201.93 95.25)
		)
		(stroke
			(width 0)
			(type default)
		)
	)
	(wire
		(pts
			(xy 176.53 97.79) (xy 176.53 100.33)
		)
		(stroke
			(width 0)
			(type default)
		)
	)
	(bus
		(pts
			(xy 181.61 205.74) (xy 181.61 208.28)
		)
		(stroke
			(width 0)
			(type default)
		)
	)
	(wire
		(pts
			(xy 254 92.71) (xy 254 97.79)
		)
		(stroke
			(width 0)
			(type default)
		)
	)
	(wire
		(pts
			(xy 226.06 85.09) (xy 243.84 85.09)
		)
		(stroke
			(width 0)
			(type default)
		)
	)
	(bus
		(pts
			(xy 181.61 215.9) (xy 181.61 218.44)
		)
		(stroke
			(width 0)
			(type default)
		)
	)
	(polyline
		(pts
			(xy 12.7 143.51) (xy 407.67 143.51)
		)
		(stroke
			(width 0)
			(type dash)
		)
	)
	(wire
		(pts
			(xy 228.6 233.68) (xy 228.6 241.3)
		)
		(stroke
			(width 0)
			(type default)
		)
	)
	(wire
		(pts
			(xy 194.31 105.41) (xy 194.31 107.95)
		)
		(stroke
			(width 0)
			(type default)
		)
	)
	(wire
		(pts
			(xy 185.42 97.79) (xy 194.31 97.79)
		)
		(stroke
			(width 0)
			(type default)
		)
	)
	(wire
		(pts
			(xy 76.2 97.79) (xy 71.12 97.79)
		)
		(stroke
			(width 0)
			(type default)
		)
	)
	(wire
		(pts
			(xy 254 105.41) (xy 243.84 105.41)
		)
		(stroke
			(width 0)
			(type default)
		)
	)
	(wire
		(pts
			(xy 228.6 80.01) (xy 228.6 77.47)
		)
		(stroke
			(width 0)
			(type default)
		)
	)
	(wire
		(pts
			(xy 254 102.87) (xy 254 105.41)
		)
		(stroke
			(width 0)
			(type default)
		)
	)
	(wire
		(pts
			(xy 167.64 97.79) (xy 176.53 97.79)
		)
		(stroke
			(width 0)
			(type default)
		)
	)
	(bus
		(pts
			(xy 181.61 208.28) (xy 181.61 210.82)
		)
		(stroke
			(width 0)
			(type default)
		)
	)
	(wire
		(pts
			(xy 194.31 233.68) (xy 201.93 233.68)
		)
		(stroke
			(width 0)
			(type default)
		)
	)
	(wire
		(pts
			(xy 201.93 95.25) (xy 204.47 95.25)
		)
		(stroke
			(width 0)
			(type default)
		)
	)
	(wire
		(pts
			(xy 176.53 97.79) (xy 185.42 97.79)
		)
		(stroke
			(width 0)
			(type default)
		)
	)
	(wire
		(pts
			(xy 167.64 100.33) (xy 167.64 97.79)
		)
		(stroke
			(width 0)
			(type default)
		)
	)
	(wire
		(pts
			(xy 226.06 80.01) (xy 228.6 80.01)
		)
		(stroke
			(width 0)
			(type default)
		)
	)
	(wire
		(pts
			(xy 176.53 233.68) (xy 185.42 233.68)
		)
		(stroke
			(width 0)
			(type default)
		)
	)
	(wire
		(pts
			(xy 204.47 226.06) (xy 201.93 226.06)
		)
		(stroke
			(width 0)
			(type default)
		)
	)
	(wire
		(pts
			(xy 176.53 233.68) (xy 176.53 236.22)
		)
		(stroke
			(width 0)
			(type default)
		)
	)
	(wire
		(pts
			(xy 204.47 62.23) (xy 184.15 62.23)
		)
		(stroke
			(width 0)
			(type default)
		)
	)
	(wire
		(pts
			(xy 86.36 105.41) (xy 86.36 107.95)
		)
		(stroke
			(width 0)
			(type default)
		)
	)
	(wire
		(pts
			(xy 226.06 228.6) (xy 254 228.6)
		)
		(stroke
			(width 0)
			(type default)
		)
	)
	(wire
		(pts
			(xy 59.69 95.25) (xy 59.69 97.79)
		)
		(stroke
			(width 0)
			(type default)
		)
	)
	(wire
		(pts
			(xy 226.06 220.98) (xy 243.84 220.98)
		)
		(stroke
			(width 0)
			(type default)
		)
	)
	(wire
		(pts
			(xy 201.93 233.68) (xy 201.93 231.14)
		)
		(stroke
			(width 0)
			(type default)
		)
	)
	(wire
		(pts
			(xy 228.6 80.01) (xy 228.6 90.17)
		)
		(stroke
			(width 0)
			(type default)
		)
	)
	(wire
		(pts
			(xy 194.31 97.79) (xy 194.31 100.33)
		)
		(stroke
			(width 0)
			(type default)
		)
	)
	(wire
		(pts
			(xy 243.84 85.09) (xy 259.08 85.09)
		)
		(stroke
			(width 0)
			(type default)
		)
	)
	(wire
		(pts
			(xy 201.93 92.71) (xy 204.47 92.71)
		)
		(stroke
			(width 0)
			(type default)
		)
	)
	(wire
		(pts
			(xy 142.24 231.14) (xy 142.24 233.68)
		)
		(stroke
			(width 0)
			(type default)
		)
	)
	(wire
		(pts
			(xy 204.47 74.93) (xy 184.15 74.93)
		)
		(stroke
			(width 0)
			(type default)
		)
	)
	(wire
		(pts
			(xy 201.93 97.79) (xy 204.47 97.79)
		)
		(stroke
			(width 0)
			(type default)
		)
	)
	(wire
		(pts
			(xy 264.16 218.44) (xy 271.78 218.44)
		)
		(stroke
			(width 0)
			(type default)
		)
	)
	(wire
		(pts
			(xy 370.84 114.3) (xy 368.3 114.3)
		)
		(stroke
			(width 0)
			(type default)
		)
	)
	(bus
		(pts
			(xy 181.61 203.2) (xy 181.61 205.74)
		)
		(stroke
			(width 0)
			(type default)
		)
	)
	(wire
		(pts
			(xy 194.31 97.79) (xy 201.93 97.79)
		)
		(stroke
			(width 0)
			(type default)
		)
	)
	(wire
		(pts
			(xy 201.93 92.71) (xy 201.93 90.17)
		)
		(stroke
			(width 0)
			(type default)
		)
	)
	(bus
		(pts
			(xy 181.61 210.82) (xy 181.61 213.36)
		)
		(stroke
			(width 0)
			(type default)
		)
	)
	(wire
		(pts
			(xy 243.84 85.09) (xy 243.84 97.79)
		)
		(stroke
			(width 0)
			(type default)
		)
	)
	(wire
		(pts
			(xy 204.47 210.82) (xy 184.15 210.82)
		)
		(stroke
			(width 0)
			(type default)
		)
	)
	(wire
		(pts
			(xy 368.3 121.92) (xy 368.3 124.46)
		)
		(stroke
			(width 0)
			(type default)
		)
	)
	(wire
		(pts
			(xy 152.4 97.79) (xy 154.94 97.79)
		)
		(stroke
			(width 0)
			(type default)
		)
	)
	(wire
		(pts
			(xy 154.94 241.3) (xy 154.94 243.84)
		)
		(stroke
			(width 0)
			(type default)
		)
	)
	(wire
		(pts
			(xy 228.6 97.79) (xy 228.6 105.41)
		)
		(stroke
			(width 0)
			(type default)
		)
	)
	(wire
		(pts
			(xy 204.47 72.39) (xy 184.15 72.39)
		)
		(stroke
			(width 0)
			(type default)
		)
	)
	(bus
		(pts
			(xy 179.07 223.52) (xy 176.53 223.52)
		)
		(stroke
			(width 0)
			(type default)
		)
	)
	(wire
		(pts
			(xy 233.68 82.55) (xy 233.68 97.79)
		)
		(stroke
			(width 0)
			(type default)
		)
	)
	(wire
		(pts
			(xy 201.93 92.71) (xy 201.93 95.25)
		)
		(stroke
			(width 0)
			(type default)
		)
	)
	(wire
		(pts
			(xy 254 238.76) (xy 254 241.3)
		)
		(stroke
			(width 0)
			(type default)
		)
	)
	(wire
		(pts
			(xy 228.6 105.41) (xy 228.6 107.95)
		)
		(stroke
			(width 0)
			(type default)
		)
	)
	(wire
		(pts
			(xy 95.25 97.79) (xy 95.25 100.33)
		)
		(stroke
			(width 0)
			(type default)
		)
	)
	(wire
		(pts
			(xy 233.68 218.44) (xy 259.08 218.44)
		)
		(stroke
			(width 0)
			(type default)
		)
	)
	(wire
		(pts
			(xy 154.94 105.41) (xy 154.94 107.95)
		)
		(stroke
			(width 0)
			(type default)
		)
	)
	(bus
		(pts
			(xy 181.61 82.55) (xy 181.61 85.09)
		)
		(stroke
			(width 0)
			(type default)
		)
	)
	(wire
		(pts
			(xy 167.64 241.3) (xy 167.64 243.84)
		)
		(stroke
			(width 0)
			(type default)
		)
	)
	(wire
		(pts
			(xy 194.31 241.3) (xy 194.31 243.84)
		)
		(stroke
			(width 0)
			(type default)
		)
	)
	(wire
		(pts
			(xy 226.06 90.17) (xy 228.6 90.17)
		)
		(stroke
			(width 0)
			(type default)
		)
	)
	(label "Ethernet_P0.D3+"
		(at 201.93 67.31 180)
		(effects
			(font
				(size 1.27 1.27)
			)
			(justify right bottom)
		)
	)
	(label "P1_CT"
		(at 200.66 233.68 180)
		(effects
			(font
				(size 1.27 1.27)
			)
			(justify right bottom)
		)
	)
	(label "Ethernet_P0.D2-"
		(at 201.93 74.93 180)
		(effects
			(font
				(size 1.27 1.27)
			)
			(justify right bottom)
		)
	)
	(label "Ethernet_P0.D1+"
		(at 201.93 77.47 180)
		(effects
			(font
				(size 1.27 1.27)
			)
			(justify right bottom)
		)
	)
	(label "Ethernet_P1.D4-"
		(at 201.93 215.9 180)
		(effects
			(font
				(size 1.27 1.27)
			)
			(justify right bottom)
		)
	)
	(label "P0_CT"
		(at 200.66 97.79 180)
		(effects
			(font
				(size 1.27 1.27)
			)
			(justify right bottom)
		)
	)
	(label "Ethernet_P1.D3-"
		(at 201.93 210.82 180)
		(effects
			(font
				(size 1.27 1.27)
			)
			(justify right bottom)
		)
	)
	(label "Ethernet_P1.D2+"
		(at 201.93 203.2 180)
		(effects
			(font
				(size 1.27 1.27)
			)
			(justify right bottom)
		)
	)
	(label "Ethernet_P1.D2-"
		(at 201.93 205.74 180)
		(effects
			(font
				(size 1.27 1.27)
			)
			(justify right bottom)
		)
	)
	(label "Ethernet_P1.D1+"
		(at 201.93 198.12 180)
		(effects
			(font
				(size 1.27 1.27)
			)
			(justify right bottom)
		)
	)
	(label "Ethernet_P0.D3-"
		(at 201.93 69.85 180)
		(effects
			(font
				(size 1.27 1.27)
			)
			(justify right bottom)
		)
	)
	(label "Ethernet_P0.D4-"
		(at 201.93 64.77 180)
		(effects
			(font
				(size 1.27 1.27)
			)
			(justify right bottom)
		)
	)
	(label "Ethernet_P1.D1-"
		(at 201.93 200.66 180)
		(effects
			(font
				(size 1.27 1.27)
			)
			(justify right bottom)
		)
	)
	(label "Ethernet_P0.D4+"
		(at 201.93 62.23 180)
		(effects
			(font
				(size 1.27 1.27)
			)
			(justify right bottom)
		)
	)
	(label "Ethernet_P0.D2+"
		(at 201.93 72.39 180)
		(effects
			(font
				(size 1.27 1.27)
			)
			(justify right bottom)
		)
	)
	(label "Ethernet_P0.D1-"
		(at 201.93 80.01 180)
		(effects
			(font
				(size 1.27 1.27)
			)
			(justify right bottom)
		)
	)
	(label "Ethernet_P1.D3+"
		(at 201.93 208.28 180)
		(effects
			(font
				(size 1.27 1.27)
			)
			(justify right bottom)
		)
	)
	(label "Ethernet_P1.D4+"
		(at 201.93 213.36 180)
		(effects
			(font
				(size 1.27 1.27)
			)
			(justify right bottom)
		)
	)
	(hierarchical_label "Ethernet_P1{10GbE}"
		(shape bidirectional)
		(at 176.53 223.52 180)
		(effects
			(font
				(size 1.27 1.27)
			)
			(justify right)
		)
	)
	(hierarchical_label "~{P0_LED_LINK_10G}"
		(shape input)
		(at 271.78 85.09 0)
		(effects
			(font
				(size 1.27 1.27)
			)
			(justify left)
		)
	)
	(hierarchical_label "~{P1_LED_ACT}"
		(shape input)
		(at 271.78 228.6 0)
		(effects
			(font
				(size 1.27 1.27)
			)
			(justify left)
		)
	)
	(hierarchical_label "~{P0_LED_ACT}"
		(shape input)
		(at 271.78 92.71 0)
		(effects
			(font
				(size 1.27 1.27)
			)
			(justify left)
		)
	)
	(hierarchical_label "~{P1_LED_LINK_10G}"
		(shape input)
		(at 271.78 220.98 0)
		(effects
			(font
				(size 1.27 1.27)
			)
			(justify left)
		)
	)
	(hierarchical_label "Ethernet_P0{10GbE}"
		(shape bidirectional)
		(at 176.53 87.63 180)
		(effects
			(font
				(size 1.27 1.27)
			)
			(justify right)
		)
	)
	(hierarchical_label "~{P1_LINK_LESS_THAN_10G}"
		(shape input)
		(at 271.78 218.44 0)
		(effects
			(font
				(size 1.27 1.27)
			)
			(justify left)
		)
	)
	(hierarchical_label "~{P0_LINK_LESS_THAN_10G}"
		(shape input)
		(at 271.78 82.55 0)
		(effects
			(font
				(size 1.27 1.27)
			)
			(justify left)
		)
	)
	(symbol
		(lib_id "antmicropower:GND")
		(at 176.53 243.84 0)
		(unit 1)
		(exclude_from_sim no)
		(in_bom yes)
		(on_board yes)
		(dnp no)
		(property "Reference" "#PWR085"
			(at 185.42 246.38 0)
			(effects
				(font
					(size 1.27 1.27)
					(thickness 0.15)
				)
				(justify left bottom)
				(hide yes)
			)
		)
		(property "Value" "GND"
			(at 176.53 247.65 0)
			(effects
				(font
					(size 1.27 1.27)
					(thickness 0.15)
				)
			)
		)
		(property "Footprint" ""
			(at 185.42 251.46 0)
			(effects
				(font
					(size 1.27 1.27)
					(thickness 0.15)
				)
				(justify left bottom)
				(hide yes)
			)
		)
		(property "Datasheet" ""
			(at 185.42 256.54 0)
			(effects
				(font
					(size 1.27 1.27)
					(thickness 0.15)
				)
				(justify left bottom)
				(hide yes)
			)
		)
		(property "Description" ""
			(at 176.53 243.84 0)
			(effects
				(font
					(size 1.27 1.27)
				)
				(hide yes)
			)
		)
		(property "Author" "Antmicro"
			(at 185.42 251.46 0)
			(effects
				(font
					(size 1.27 1.27)
					(thickness 0.15)
				)
				(justify left bottom)
				(hide yes)
			)
		)
		(property "License" "Apache-2.0"
			(at 185.42 254 0)
			(effects
				(font
					(size 1.27 1.27)
					(thickness 0.15)
				)
				(justify left bottom)
				(hide yes)
			)
		)
		(pin "1"
		)
		(instances
			(project "OCuLink to 10GbE adapter"
				(path ""
					(reference "#PWR085")
					(unit 1)
				)
			)
		)
	)
	(symbol
		(lib_id "antmicroResistors0402:R_220R_0402")
		(at 259.08 85.09 0)
		(unit 1)
		(exclude_from_sim no)
		(in_bom yes)
		(on_board yes)
		(dnp no)
		(property "Reference" "R37"
			(at 259.08 83.82 0)
			(effects
				(font
					(size 1.27 1.27)
					(thickness 0.15)
				)
				(justify right)
			)
		)
		(property "Value" "R_220R_0402"
			(at 279.4 97.79 0)
			(effects
				(font
					(size 1.27 1.27)
					(thickness 0.15)
				)
				(justify left bottom)
				(hide yes)
			)
		)
		(property "Footprint" "antmicro-footprints:R_0402_1005Metric"
			(at 279.4 100.33 0)
			(effects
				(font
					(size 1.27 1.27)
					(thickness 0.15)
				)
				(justify left bottom)
				(hide yes)
			)
		)
		(property "Datasheet" "https://www.bourns.com/docs/product-datasheets/cr.pdf"
			(at 279.4 102.87 0)
			(effects
				(font
					(size 1.27 1.27)
					(thickness 0.15)
				)
				(justify left bottom)
				(hide yes)
			)
		)
		(property "Description" "SMD Chip Resistor, 220 ohm, ± 1%, 62.5 mW, 0402 [1005 Metric], Thick Film, General Purpose"
			(at 259.08 85.09 0)
			(effects
				(font
					(size 1.27 1.27)
				)
				(hide yes)
			)
		)
		(property "MPN" "CR0402-FX-2200GLF"
			(at 279.4 105.41 0)
			(effects
				(font
					(size 1.27 1.27)
					(thickness 0.15)
				)
				(justify left bottom)
				(hide yes)
			)
		)
		(property "Manufacturer" "Bourns"
			(at 279.4 107.95 0)
			(effects
				(font
					(size 1.27 1.27)
					(thickness 0.15)
				)
				(justify left bottom)
				(hide yes)
			)
		)
		(property "License" "Apache-2.0"
			(at 279.4 110.49 0)
			(effects
				(font
					(size 1.27 1.27)
					(thickness 0.15)
				)
				(justify left bottom)
				(hide yes)
			)
		)
		(property "Author" "Antmicro"
			(at 279.4 113.03 0)
			(effects
				(font
					(size 1.27 1.27)
					(thickness 0.15)
				)
				(justify left bottom)
				(hide yes)
			)
		)
		(property "Val" "220R"
			(at 264.16 83.82 0)
			(effects
				(font
					(size 1.27 1.27)
					(thickness 0.15)
				)
				(justify left)
			)
		)
		(property "Tolerance" "1%"
			(at 279.4 95.25 0)
			(effects
				(font
					(size 1.27 1.27)
				)
				(justify left bottom)
				(hide yes)
			)
		)
		(pin "1"
		)
		(pin "2"
		)
		(instances
			(project "OCuLink to 10GbE adapter"
				(path ""
					(reference "R37")
					(unit 1)
				)
			)
		)
	)
	(symbol
		(lib_id "antmicroMechanicalParts:MP_Terminal_M3_THT_7760")
		(at 370.84 121.92 0)
		(unit 1)
		(exclude_from_sim no)
		(in_bom yes)
		(on_board yes)
		(dnp no)
		(fields_autoplaced yes)
		(property "Reference" "J5"
			(at 379.73 120.65 0)
			(effects
				(font
					(size 1.27 1.27)
					(thickness 0.15)
				)
				(justify left)
			)
		)
		(property "Value" "MP_Terminal_M3_THT_7760"
			(at 393.7 129.54 0)
			(effects
				(font
					(size 1.27 1.27)
					(thickness 0.15)
				)
				(justify left bottom)
				(hide yes)
			)
		)
		(property "Footprint" "antmicro-footprints:MP_Terminal_M3_THT_7760"
			(at 393.7 132.08 0)
			(effects
				(font
					(size 1.27 1.27)
					(thickness 0.15)
				)
				(justify left bottom)
				(hide yes)
			)
		)
		(property "Datasheet" "https://www.mouser.com/datasheet/2/215/7760-741244.pdf"
			(at 393.7 134.62 0)
			(effects
				(font
					(size 1.27 1.27)
					(thickness 0.15)
				)
				(justify left bottom)
				(hide yes)
			)
		)
		(property "Description" "PCB Terminal, 90° THT, Brass, Tin"
			(at 393.7 137.16 0)
			(effects
				(font
					(size 1.27 1.27)
					(thickness 0.15)
				)
				(justify left bottom)
				(hide yes)
			)
		)
		(property "MPN" "7760"
			(at 379.73 123.19 0)
			(effects
				(font
					(size 1.27 1.27)
					(thickness 0.15)
				)
				(justify left)
			)
		)
		(property "Manufacturer" "Keystone Electronics"
			(at 393.7 139.7 0)
			(effects
				(font
					(size 1.27 1.27)
					(thickness 0.15)
				)
				(justify left bottom)
				(hide yes)
			)
		)
		(property "Author" "Antmicro"
			(at 393.7 142.24 0)
			(effects
				(font
					(size 1.27 1.27)
					(thickness 0.15)
				)
				(justify left bottom)
				(hide yes)
			)
		)
		(property "License" "Apache-2.0"
			(at 393.7 144.78 0)
			(effects
				(font
					(size 1.27 1.27)
					(thickness 0.15)
				)
				(justify left bottom)
				(hide yes)
			)
		)
		(pin "1"
		)
		(instances
			(project "OCuLink to 10GbE adapter"
				(path ""
					(reference "J5")
					(unit 1)
				)
			)
		)
	)
	(symbol
		(lib_id "antmicropower:GND")
		(at 228.6 107.95 0)
		(unit 1)
		(exclude_from_sim no)
		(in_bom yes)
		(on_board yes)
		(dnp no)
		(property "Reference" "#PWR079"
			(at 237.49 110.49 0)
			(effects
				(font
					(size 1.27 1.27)
					(thickness 0.15)
				)
				(justify left bottom)
				(hide yes)
			)
		)
		(property "Value" "GND"
			(at 228.6 111.76 0)
			(effects
				(font
					(size 1.27 1.27)
					(thickness 0.15)
				)
			)
		)
		(property "Footprint" ""
			(at 237.49 115.57 0)
			(effects
				(font
					(size 1.27 1.27)
					(thickness 0.15)
				)
				(justify left bottom)
				(hide yes)
			)
		)
		(property "Datasheet" ""
			(at 237.49 120.65 0)
			(effects
				(font
					(size 1.27 1.27)
					(thickness 0.15)
				)
				(justify left bottom)
				(hide yes)
			)
		)
		(property "Description" ""
			(at 228.6 107.95 0)
			(effects
				(font
					(size 1.27 1.27)
				)
				(hide yes)
			)
		)
		(property "Author" "Antmicro"
			(at 237.49 115.57 0)
			(effects
				(font
					(size 1.27 1.27)
					(thickness 0.15)
				)
				(justify left bottom)
				(hide yes)
			)
		)
		(property "License" "Apache-2.0"
			(at 237.49 118.11 0)
			(effects
				(font
					(size 1.27 1.27)
					(thickness 0.15)
				)
				(justify left bottom)
				(hide yes)
			)
		)
		(pin "1"
		)
		(instances
			(project "OCuLink to 10GbE adapter"
				(path ""
					(reference "#PWR079")
					(unit 1)
				)
			)
		)
	)
	(symbol
		(lib_id "antmicroCapacitors0402:C_1u_25V_0402")
		(at 185.42 105.41 90)
		(unit 1)
		(exclude_from_sim no)
		(in_bom yes)
		(on_board yes)
		(dnp no)
		(property "Reference" "C58"
			(at 187.452 101.6 90)
			(effects
				(font
					(size 1.27 1.27)
					(thickness 0.15)
				)
				(justify right)
			)
		)
		(property "Value" "C_1u_25V_0402"
			(at 195.58 85.09 0)
			(effects
				(font
					(size 1.27 1.27)
					(thickness 0.15)
				)
				(justify left bottom)
				(hide yes)
			)
		)
		(property "Footprint" "antmicro-footprints:C_0402_1005Metric"
			(at 198.12 85.09 0)
			(effects
				(font
					(size 1.27 1.27)
					(thickness 0.15)
				)
				(justify left bottom)
				(hide yes)
			)
		)
		(property "Datasheet" "https://www.murata.com/products/productdetail?partno=GRM155R61E105KE11%23"
			(at 200.66 85.09 0)
			(effects
				(font
					(size 1.27 1.27)
					(thickness 0.15)
				)
				(justify left bottom)
				(hide yes)
			)
		)
		(property "Description" "SMD Multilayer Ceramic Capacitor, 1 µF, 25 V, 0402 [1005 Metric], ± 10%, X5R, GRM Series"
			(at 185.42 105.41 0)
			(effects
				(font
					(size 1.27 1.27)
				)
				(hide yes)
			)
		)
		(property "MPN" "GRM155R61E105KE11J"
			(at 203.2 85.09 0)
			(effects
				(font
					(size 1.27 1.27)
					(thickness 0.15)
				)
				(justify left bottom)
				(hide yes)
			)
		)
		(property "Manufacturer" "Murata"
			(at 205.74 85.09 0)
			(effects
				(font
					(size 1.27 1.27)
					(thickness 0.15)
				)
				(justify left bottom)
				(hide yes)
			)
		)
		(property "License" "Apache-2.0"
			(at 208.28 85.09 0)
			(effects
				(font
					(size 1.27 1.27)
					(thickness 0.15)
				)
				(justify left bottom)
				(hide yes)
			)
		)
		(property "Author" "Antmicro"
			(at 210.82 85.09 0)
			(effects
				(font
					(size 1.27 1.27)
					(thickness 0.15)
				)
				(justify left bottom)
				(hide yes)
			)
		)
		(property "Val" "1u"
			(at 187.452 104.14 90)
			(effects
				(font
					(size 1.27 1.27)
					(thickness 0.15)
				)
				(justify right)
			)
		)
		(property "Voltage" "25V"
			(at 213.36 85.09 0)
			(effects
				(font
					(size 1.27 1.27)
				)
				(justify left bottom)
				(hide yes)
			)
		)
		(property "Dielectric" "X5R"
			(at 215.9 85.09 0)
			(effects
				(font
					(size 1.27 1.27)
				)
				(justify left bottom)
				(hide yes)
			)
		)
		(pin "1"
		)
		(pin "2"
		)
		(instances
			(project "OCuLink to 10GbE adapter"
				(path ""
					(reference "C58")
					(unit 1)
				)
			)
		)
	)
	(symbol
		(lib_id "antmicroCapacitors0402:C_470p_0402")
		(at 233.68 102.87 90)
		(unit 1)
		(exclude_from_sim no)
		(in_bom yes)
		(on_board yes)
		(dnp no)
		(property "Reference" "C48"
			(at 235.712 99.06 90)
			(effects
				(font
					(size 1.27 1.27)
					(thickness 0.15)
				)
				(justify right)
			)
		)
		(property "Value" "C_470p_0402"
			(at 243.84 82.55 0)
			(effects
				(font
					(size 1.27 1.27)
					(thickness 0.15)
				)
				(justify left bottom)
				(hide yes)
			)
		)
		(property "Footprint" "antmicro-footprints:C_0402_1005Metric"
			(at 246.38 82.55 0)
			(effects
				(font
					(size 1.27 1.27)
					(thickness 0.15)
				)
				(justify left bottom)
				(hide yes)
			)
		)
		(property "Datasheet" "https://www.passivecomponent.com/wp-content/uploads/datasheet/WTC_MLCC_General_Purpose.pdf"
			(at 248.92 82.55 0)
			(effects
				(font
					(size 1.27 1.27)
					(thickness 0.15)
				)
				(justify left bottom)
				(hide yes)
			)
		)
		(property "Description" "SMD Multilayer Ceramic Capacitor, General Purpose, 470 pF, 25 V, 0402 [1005 Metric], ± 10%, X7R"
			(at 233.68 102.87 0)
			(effects
				(font
					(size 1.27 1.27)
				)
				(hide yes)
			)
		)
		(property "MPN" "0402B471K250CT"
			(at 251.46 82.55 0)
			(effects
				(font
					(size 1.27 1.27)
					(thickness 0.15)
				)
				(justify left bottom)
				(hide yes)
			)
		)
		(property "Manufacturer" "Walsin"
			(at 254 82.55 0)
			(effects
				(font
					(size 1.27 1.27)
					(thickness 0.15)
				)
				(justify left bottom)
				(hide yes)
			)
		)
		(property "License" "Apache-2.0"
			(at 256.54 82.55 0)
			(effects
				(font
					(size 1.27 1.27)
					(thickness 0.15)
				)
				(justify left bottom)
				(hide yes)
			)
		)
		(property "Author" "Antmicro"
			(at 259.08 82.55 0)
			(effects
				(font
					(size 1.27 1.27)
					(thickness 0.15)
				)
				(justify left bottom)
				(hide yes)
			)
		)
		(property "Val" "470p"
			(at 235.712 101.6 90)
			(effects
				(font
					(size 1.27 1.27)
					(thickness 0.15)
				)
				(justify right)
			)
		)
		(property "Voltage" "25V"
			(at 261.62 82.55 0)
			(effects
				(font
					(size 1.27 1.27)
				)
				(justify left bottom)
				(hide yes)
			)
		)
		(property "Dielectric" "X7R"
			(at 264.16 82.55 0)
			(effects
				(font
					(size 1.27 1.27)
				)
				(justify left bottom)
				(hide yes)
			)
		)
		(pin "2"
		)
		(pin "1"
		)
		(instances
			(project ""
				(path ""
					(reference "C48")
					(unit 1)
				)
			)
		)
	)
	(symbol
		(lib_id "antmicroMechanicalParts:MP_Terminal_M3_THT_7760")
		(at 370.84 114.3 0)
		(unit 1)
		(exclude_from_sim no)
		(in_bom yes)
		(on_board yes)
		(dnp no)
		(fields_autoplaced yes)
		(property "Reference" "J4"
			(at 379.73 113.03 0)
			(effects
				(font
					(size 1.27 1.27)
					(thickness 0.15)
				)
				(justify left)
			)
		)
		(property "Value" "MP_Terminal_M3_THT_7760"
			(at 393.7 121.92 0)
			(effects
				(font
					(size 1.27 1.27)
					(thickness 0.15)
				)
				(justify left bottom)
				(hide yes)
			)
		)
		(property "Footprint" "antmicro-footprints:MP_Terminal_M3_THT_7760"
			(at 393.7 124.46 0)
			(effects
				(font
					(size 1.27 1.27)
					(thickness 0.15)
				)
				(justify left bottom)
				(hide yes)
			)
		)
		(property "Datasheet" "https://www.mouser.com/datasheet/2/215/7760-741244.pdf"
			(at 393.7 127 0)
			(effects
				(font
					(size 1.27 1.27)
					(thickness 0.15)
				)
				(justify left bottom)
				(hide yes)
			)
		)
		(property "Description" "PCB Terminal, 90° THT, Brass, Tin"
			(at 393.7 129.54 0)
			(effects
				(font
					(size 1.27 1.27)
					(thickness 0.15)
				)
				(justify left bottom)
				(hide yes)
			)
		)
		(property "MPN" "7760"
			(at 379.73 115.57 0)
			(effects
				(font
					(size 1.27 1.27)
					(thickness 0.15)
				)
				(justify left)
			)
		)
		(property "Manufacturer" "Keystone Electronics"
			(at 393.7 132.08 0)
			(effects
				(font
					(size 1.27 1.27)
					(thickness 0.15)
				)
				(justify left bottom)
				(hide yes)
			)
		)
		(property "Author" "Antmicro"
			(at 393.7 134.62 0)
			(effects
				(font
					(size 1.27 1.27)
					(thickness 0.15)
				)
				(justify left bottom)
				(hide yes)
			)
		)
		(property "License" "Apache-2.0"
			(at 393.7 137.16 0)
			(effects
				(font
					(size 1.27 1.27)
					(thickness 0.15)
				)
				(justify left bottom)
				(hide yes)
			)
		)
		(pin "1"
		)
		(instances
			(project "OCuLink to 10GbE adapter"
				(path ""
					(reference "J4")
					(unit 1)
				)
			)
		)
	)
	(symbol
		(lib_id "antmicroCapacitorsmisc:C_100u_0805")
		(at 154.94 241.3 90)
		(unit 1)
		(exclude_from_sim no)
		(in_bom yes)
		(on_board yes)
		(dnp no)
		(property "Reference" "C63"
			(at 156.972 237.49 90)
			(effects
				(font
					(size 1.27 1.27)
					(thickness 0.15)
				)
				(justify right)
			)
		)
		(property "Value" "C_100u_0805"
			(at 165.1 220.98 0)
			(effects
				(font
					(size 1.27 1.27)
					(thickness 0.15)
				)
				(justify left bottom)
				(hide yes)
			)
		)
		(property "Footprint" "antmicro-footprints:C_0805_2012Metric"
			(at 167.64 220.98 0)
			(effects
				(font
					(size 1.27 1.27)
					(thickness 0.15)
				)
				(justify left bottom)
				(hide yes)
			)
		)
		(property "Datasheet" "https://www.murata.com/products/productdetail?partno=GRM21BR60J107ME15%23"
			(at 170.18 220.98 0)
			(effects
				(font
					(size 1.27 1.27)
					(thickness 0.15)
				)
				(justify left bottom)
				(hide yes)
			)
		)
		(property "Description" "SMD Multilayer Ceramic Capacitor, 100 µF, 6.3 V, 0805 [2012 Metric], ± 20%, X5R, GRM Series"
			(at 154.94 241.3 0)
			(effects
				(font
					(size 1.27 1.27)
				)
				(hide yes)
			)
		)
		(property "MPN" "GRM21BR60J107ME15L"
			(at 172.72 220.98 0)
			(effects
				(font
					(size 1.27 1.27)
					(thickness 0.15)
				)
				(justify left bottom)
				(hide yes)
			)
		)
		(property "Manufacturer" "Murata"
			(at 175.26 220.98 0)
			(effects
				(font
					(size 1.27 1.27)
					(thickness 0.15)
				)
				(justify left bottom)
				(hide yes)
			)
		)
		(property "License" "Apache-2.0"
			(at 177.8 220.98 0)
			(effects
				(font
					(size 1.27 1.27)
					(thickness 0.15)
				)
				(justify left bottom)
				(hide yes)
			)
		)
		(property "Author" "Antmicro"
			(at 180.34 220.98 0)
			(effects
				(font
					(size 1.27 1.27)
					(thickness 0.15)
				)
				(justify left bottom)
				(hide yes)
			)
		)
		(property "Val" "100u"
			(at 156.972 240.03 90)
			(effects
				(font
					(size 1.27 1.27)
					(thickness 0.15)
				)
				(justify right)
			)
		)
		(property "Voltage" ""
			(at 182.88 220.98 0)
			(effects
				(font
					(size 1.27 1.27)
				)
				(justify left bottom)
				(hide yes)
			)
		)
		(property "Dielectric" ""
			(at 185.42 220.98 0)
			(effects
				(font
					(size 1.27 1.27)
				)
				(justify left bottom)
				(hide yes)
			)
		)
		(property "Public" "False"
			(at 187.96 220.98 0)
			(effects
				(font
					(size 1.27 1.27)
				)
				(justify left bottom)
				(hide yes)
			)
		)
		(pin "1"
		)
		(pin "2"
		)
		(instances
			(project "OCuLink to 10GbE adapter"
				(path ""
					(reference "C63")
					(unit 1)
				)
			)
		)
	)
	(symbol
		(lib_id "antmicroResistors0402:R_220R_0402")
		(at 259.08 220.98 0)
		(unit 1)
		(exclude_from_sim no)
		(in_bom yes)
		(on_board yes)
		(dnp no)
		(property "Reference" "R40"
			(at 259.08 219.71 0)
			(effects
				(font
					(size 1.27 1.27)
					(thickness 0.15)
				)
				(justify right)
			)
		)
		(property "Value" "R_220R_0402"
			(at 279.4 233.68 0)
			(effects
				(font
					(size 1.27 1.27)
					(thickness 0.15)
				)
				(justify left bottom)
				(hide yes)
			)
		)
		(property "Footprint" "antmicro-footprints:R_0402_1005Metric"
			(at 279.4 236.22 0)
			(effects
				(font
					(size 1.27 1.27)
					(thickness 0.15)
				)
				(justify left bottom)
				(hide yes)
			)
		)
		(property "Datasheet" "https://www.bourns.com/docs/product-datasheets/cr.pdf"
			(at 279.4 238.76 0)
			(effects
				(font
					(size 1.27 1.27)
					(thickness 0.15)
				)
				(justify left bottom)
				(hide yes)
			)
		)
		(property "Description" "SMD Chip Resistor, 220 ohm, ± 1%, 62.5 mW, 0402 [1005 Metric], Thick Film, General Purpose"
			(at 259.08 220.98 0)
			(effects
				(font
					(size 1.27 1.27)
				)
				(hide yes)
			)
		)
		(property "MPN" "CR0402-FX-2200GLF"
			(at 279.4 241.3 0)
			(effects
				(font
					(size 1.27 1.27)
					(thickness 0.15)
				)
				(justify left bottom)
				(hide yes)
			)
		)
		(property "Manufacturer" "Bourns"
			(at 279.4 243.84 0)
			(effects
				(font
					(size 1.27 1.27)
					(thickness 0.15)
				)
				(justify left bottom)
				(hide yes)
			)
		)
		(property "License" "Apache-2.0"
			(at 279.4 246.38 0)
			(effects
				(font
					(size 1.27 1.27)
					(thickness 0.15)
				)
				(justify left bottom)
				(hide yes)
			)
		)
		(property "Author" "Antmicro"
			(at 279.4 248.92 0)
			(effects
				(font
					(size 1.27 1.27)
					(thickness 0.15)
				)
				(justify left bottom)
				(hide yes)
			)
		)
		(property "Val" "220R"
			(at 264.16 219.71 0)
			(effects
				(font
					(size 1.27 1.27)
					(thickness 0.15)
				)
				(justify left)
			)
		)
		(property "Tolerance" "1%"
			(at 279.4 231.14 0)
			(effects
				(font
					(size 1.27 1.27)
				)
				(justify left bottom)
				(hide yes)
			)
		)
		(pin "1"
		)
		(pin "2"
		)
		(instances
			(project "OCuLink to 10GbE adapter"
				(path ""
					(reference "R40")
					(unit 1)
				)
			)
		)
	)
	(symbol
		(lib_id "antmicroCapacitors0402:C_470p_0402")
		(at 243.84 238.76 90)
		(unit 1)
		(exclude_from_sim no)
		(in_bom yes)
		(on_board yes)
		(dnp no)
		(property "Reference" "C61"
			(at 245.872 234.95 90)
			(effects
				(font
					(size 1.27 1.27)
					(thickness 0.15)
				)
				(justify right)
			)
		)
		(property "Value" "C_470p_0402"
			(at 254 218.44 0)
			(effects
				(font
					(size 1.27 1.27)
					(thickness 0.15)
				)
				(justify left bottom)
				(hide yes)
			)
		)
		(property "Footprint" "antmicro-footprints:C_0402_1005Metric"
			(at 256.54 218.44 0)
			(effects
				(font
					(size 1.27 1.27)
					(thickness 0.15)
				)
				(justify left bottom)
				(hide yes)
			)
		)
		(property "Datasheet" "https://www.passivecomponent.com/wp-content/uploads/datasheet/WTC_MLCC_General_Purpose.pdf"
			(at 259.08 218.44 0)
			(effects
				(font
					(size 1.27 1.27)
					(thickness 0.15)
				)
				(justify left bottom)
				(hide yes)
			)
		)
		(property "Description" "SMD Multilayer Ceramic Capacitor, General Purpose, 470 pF, 25 V, 0402 [1005 Metric], ± 10%, X7R"
			(at 243.84 238.76 0)
			(effects
				(font
					(size 1.27 1.27)
				)
				(hide yes)
			)
		)
		(property "MPN" "0402B471K250CT"
			(at 261.62 218.44 0)
			(effects
				(font
					(size 1.27 1.27)
					(thickness 0.15)
				)
				(justify left bottom)
				(hide yes)
			)
		)
		(property "Manufacturer" "Walsin"
			(at 264.16 218.44 0)
			(effects
				(font
					(size 1.27 1.27)
					(thickness 0.15)
				)
				(justify left bottom)
				(hide yes)
			)
		)
		(property "License" "Apache-2.0"
			(at 266.7 218.44 0)
			(effects
				(font
					(size 1.27 1.27)
					(thickness 0.15)
				)
				(justify left bottom)
				(hide yes)
			)
		)
		(property "Author" "Antmicro"
			(at 269.24 218.44 0)
			(effects
				(font
					(size 1.27 1.27)
					(thickness 0.15)
				)
				(justify left bottom)
				(hide yes)
			)
		)
		(property "Val" "470p"
			(at 245.872 237.49 90)
			(effects
				(font
					(size 1.27 1.27)
					(thickness 0.15)
				)
				(justify right)
			)
		)
		(property "Voltage" "25V"
			(at 271.78 218.44 0)
			(effects
				(font
					(size 1.27 1.27)
				)
				(justify left bottom)
				(hide yes)
			)
		)
		(property "Dielectric" "X7R"
			(at 274.32 218.44 0)
			(effects
				(font
					(size 1.27 1.27)
				)
				(justify left bottom)
				(hide yes)
			)
		)
		(pin "2"
		)
		(pin "1"
		)
		(instances
			(project "OCuLink to 10GbE adapter"
				(path ""
					(reference "C61")
					(unit 1)
				)
			)
		)
	)
	(symbol
		(lib_id "antmicropower:GND")
		(at 167.64 107.95 0)
		(unit 1)
		(exclude_from_sim no)
		(in_bom yes)
		(on_board yes)
		(dnp no)
		(property "Reference" "#PWR075"
			(at 176.53 110.49 0)
			(effects
				(font
					(size 1.27 1.27)
					(thickness 0.15)
				)
				(justify left bottom)
				(hide yes)
			)
		)
		(property "Value" "GND"
			(at 167.64 111.76 0)
			(effects
				(font
					(size 1.27 1.27)
					(thickness 0.15)
				)
			)
		)
		(property "Footprint" ""
			(at 176.53 115.57 0)
			(effects
				(font
					(size 1.27 1.27)
					(thickness 0.15)
				)
				(justify left bottom)
				(hide yes)
			)
		)
		(property "Datasheet" ""
			(at 176.53 120.65 0)
			(effects
				(font
					(size 1.27 1.27)
					(thickness 0.15)
				)
				(justify left bottom)
				(hide yes)
			)
		)
		(property "Description" ""
			(at 167.64 107.95 0)
			(effects
				(font
					(size 1.27 1.27)
				)
				(hide yes)
			)
		)
		(property "Author" "Antmicro"
			(at 176.53 115.57 0)
			(effects
				(font
					(size 1.27 1.27)
					(thickness 0.15)
				)
				(justify left bottom)
				(hide yes)
			)
		)
		(property "License" "Apache-2.0"
			(at 176.53 118.11 0)
			(effects
				(font
					(size 1.27 1.27)
					(thickness 0.15)
				)
				(justify left bottom)
				(hide yes)
			)
		)
		(pin "1"
		)
		(instances
			(project "OCuLink to 10GbE adapter"
				(path ""
					(reference "#PWR075")
					(unit 1)
				)
			)
		)
	)
	(symbol
		(lib_id "antmicroModularConnectorsJacksWithMagnetics:Bus_RJ45_JTH-0024NL")
		(at 204.47 198.12 0)
		(unit 1)
		(exclude_from_sim no)
		(in_bom yes)
		(on_board yes)
		(dnp no)
		(fields_autoplaced yes)
		(property "Reference" "J6"
			(at 215.265 190.5 0)
			(effects
				(font
					(size 1.27 1.27)
					(thickness 0.15)
				)
			)
		)
		(property "Value" "Bus_RJ45_JTH-0024NL"
			(at 240.03 203.2 0)
			(effects
				(font
					(size 1.27 1.27)
					(thickness 0.15)
				)
				(justify left bottom)
				(hide yes)
			)
		)
		(property "Footprint" "antmicro-footprints:RJ45_JTH-0024NL"
			(at 240.03 205.74 0)
			(effects
				(font
					(size 1.27 1.27)
					(thickness 0.15)
				)
				(justify left bottom)
				(hide yes)
			)
		)
		(property "Datasheet" "https://www.mouser.com/datasheet/2/447/JTH_0024NL-3072047.pdf"
			(at 240.03 208.28 0)
			(effects
				(font
					(size 1.27 1.27)
					(thickness 0.15)
				)
				(justify left bottom)
				(hide yes)
			)
		)
		(property "Description" "Modular Connectors / Ethernet Connectors 1X1 TAB DOWN W/LED'S ETHERNET (NON PoE)"
			(at 204.47 198.12 0)
			(effects
				(font
					(size 1.27 1.27)
				)
				(hide yes)
			)
		)
		(property "MPN" "JTH-0024NL"
			(at 215.265 193.04 0)
			(effects
				(font
					(size 1.27 1.27)
					(thickness 0.15)
				)
			)
		)
		(property "Manufacturer" "Pulse Electronics"
			(at 240.03 213.36 0)
			(effects
				(font
					(size 1.27 1.27)
					(thickness 0.15)
				)
				(justify left bottom)
				(hide yes)
			)
		)
		(property "Author" "Antmicro"
			(at 240.03 215.9 0)
			(effects
				(font
					(size 1.27 1.27)
					(thickness 0.15)
				)
				(justify left bottom)
				(hide yes)
			)
		)
		(property "License" "Apache-2.0"
			(at 240.03 218.44 0)
			(effects
				(font
					(size 1.27 1.27)
					(thickness 0.15)
				)
				(justify left bottom)
				(hide yes)
			)
		)
		(pin "8"
		)
		(pin "14"
		)
		(pin "9"
		)
		(pin "11"
		)
		(pin "10"
		)
		(pin "SH"
		)
		(pin "13"
		)
		(pin "17"
		)
		(pin "6"
		)
		(pin "12"
		)
		(pin "1"
		)
		(pin "2"
		)
		(pin "4"
		)
		(pin "5"
		)
		(pin "3"
		)
		(pin "7"
		)
		(pin "15"
		)
		(pin "16"
		)
		(instances
			(project "OCuLink to 10GbE adapter"
				(path ""
					(reference "J6")
					(unit 1)
				)
			)
		)
	)
	(symbol
		(lib_id "antmicroFixedInductors:L_2n4_0.85A_0402")
		(at 147.32 233.68 0)
		(unit 1)
		(exclude_from_sim no)
		(in_bom yes)
		(on_board yes)
		(dnp no)
		(property "Reference" "L7"
			(at 149.86 229.108 0)
			(effects
				(font
					(size 1.27 1.27)
					(thickness 0.15)
				)
			)
		)
		(property "Value" "L_2n4_0.85A_0402"
			(at 161.29 236.22 0)
			(effects
				(font
					(size 1.27 1.27)
					(thickness 0.15)
				)
				(justify left bottom)
				(hide yes)
			)
		)
		(property "Footprint" "antmicro-footprints:L_0402_1005Metric"
			(at 161.29 241.3 0)
			(effects
				(font
					(size 1.27 1.27)
					(thickness 0.15)
				)
				(justify left bottom)
				(hide yes)
			)
		)
		(property "Datasheet" "https://www.murata.com/products/productdetail?partno=LQW15AN2N4B00%23"
			(at 161.29 243.84 0)
			(effects
				(font
					(size 1.27 1.27)
					(thickness 0.15)
				)
				(justify left bottom)
				(hide yes)
			)
		)
		(property "Description" "Wirewound Inductor, 2.4 nH, 0.05 ohm, 15 GHz, 850 mA, 0402 [1005 Metric], LQW15AN"
			(at 147.32 233.68 0)
			(effects
				(font
					(size 1.27 1.27)
				)
				(hide yes)
			)
		)
		(property "Val" "2n4/0.85A"
			(at 149.86 231.648 0)
			(effects
				(font
					(size 1.27 1.27)
					(thickness 0.15)
				)
			)
		)
		(property "Manufacturer" "Murata"
			(at 161.29 246.38 0)
			(effects
				(font
					(size 1.27 1.27)
					(thickness 0.15)
				)
				(justify left bottom)
				(hide yes)
			)
		)
		(property "MPN" "LQW15AN2N4B00D"
			(at 161.29 248.92 0)
			(effects
				(font
					(size 1.27 1.27)
					(thickness 0.15)
				)
				(justify left bottom)
				(hide yes)
			)
		)
		(property "ISat" "0.85 A"
			(at 161.29 250.19 0)
			(effects
				(font
					(size 1.27 1.27)
				)
				(justify left)
				(hide yes)
			)
		)
		(property "IMax" "0.85 A"
			(at 161.29 254 0)
			(effects
				(font
					(size 1.27 1.27)
					(thickness 0.15)
				)
				(justify left bottom)
				(hide yes)
			)
		)
		(property "Size" "1.0x0.5"
			(at 161.29 256.54 0)
			(effects
				(font
					(size 1.27 1.27)
					(thickness 0.15)
				)
				(justify left bottom)
				(hide yes)
			)
		)
		(property "Author" "Antmicro"
			(at 161.29 259.08 0)
			(effects
				(font
					(size 1.27 1.27)
					(thickness 0.15)
				)
				(justify left bottom)
				(hide yes)
			)
		)
		(property "License" "Apache-2.0"
			(at 161.29 261.62 0)
			(effects
				(font
					(size 1.27 1.27)
					(thickness 0.15)
				)
				(justify left bottom)
				(hide yes)
			)
		)
		(pin "2"
		)
		(pin "1"
		)
		(instances
			(project "OCuLink to 10GbE adapter"
				(path ""
					(reference "L7")
					(unit 1)
				)
			)
		)
	)
	(symbol
		(lib_id "antmicropower:GND")
		(at 86.36 107.95 0)
		(unit 1)
		(exclude_from_sim no)
		(in_bom yes)
		(on_board yes)
		(dnp no)
		(property "Reference" "#PWR072"
			(at 95.25 110.49 0)
			(effects
				(font
					(size 1.27 1.27)
					(thickness 0.15)
				)
				(justify left bottom)
				(hide yes)
			)
		)
		(property "Value" "GND"
			(at 86.36 111.76 0)
			(effects
				(font
					(size 1.27 1.27)
					(thickness 0.15)
				)
			)
		)
		(property "Footprint" ""
			(at 95.25 115.57 0)
			(effects
				(font
					(size 1.27 1.27)
					(thickness 0.15)
				)
				(justify left bottom)
				(hide yes)
			)
		)
		(property "Datasheet" ""
			(at 95.25 120.65 0)
			(effects
				(font
					(size 1.27 1.27)
					(thickness 0.15)
				)
				(justify left bottom)
				(hide yes)
			)
		)
		(property "Description" ""
			(at 86.36 107.95 0)
			(effects
				(font
					(size 1.27 1.27)
				)
				(hide yes)
			)
		)
		(property "Author" "Antmicro"
			(at 95.25 115.57 0)
			(effects
				(font
					(size 1.27 1.27)
					(thickness 0.15)
				)
				(justify left bottom)
				(hide yes)
			)
		)
		(property "License" "Apache-2.0"
			(at 95.25 118.11 0)
			(effects
				(font
					(size 1.27 1.27)
					(thickness 0.15)
				)
				(justify left bottom)
				(hide yes)
			)
		)
		(pin "1"
		)
		(instances
			(project "OCuLink to 10GbE adapter"
				(path ""
					(reference "#PWR072")
					(unit 1)
				)
			)
		)
	)
	(symbol
		(lib_id "antmicroCapacitors0402:C_470p_0402")
		(at 243.84 102.87 90)
		(unit 1)
		(exclude_from_sim no)
		(in_bom yes)
		(on_board yes)
		(dnp no)
		(property "Reference" "C49"
			(at 245.872 99.06 90)
			(effects
				(font
					(size 1.27 1.27)
					(thickness 0.15)
				)
				(justify right)
			)
		)
		(property "Value" "C_470p_0402"
			(at 254 82.55 0)
			(effects
				(font
					(size 1.27 1.27)
					(thickness 0.15)
				)
				(justify left bottom)
				(hide yes)
			)
		)
		(property "Footprint" "antmicro-footprints:C_0402_1005Metric"
			(at 256.54 82.55 0)
			(effects
				(font
					(size 1.27 1.27)
					(thickness 0.15)
				)
				(justify left bottom)
				(hide yes)
			)
		)
		(property "Datasheet" "https://www.passivecomponent.com/wp-content/uploads/datasheet/WTC_MLCC_General_Purpose.pdf"
			(at 259.08 82.55 0)
			(effects
				(font
					(size 1.27 1.27)
					(thickness 0.15)
				)
				(justify left bottom)
				(hide yes)
			)
		)
		(property "Description" "SMD Multilayer Ceramic Capacitor, General Purpose, 470 pF, 25 V, 0402 [1005 Metric], ± 10%, X7R"
			(at 243.84 102.87 0)
			(effects
				(font
					(size 1.27 1.27)
				)
				(hide yes)
			)
		)
		(property "MPN" "0402B471K250CT"
			(at 261.62 82.55 0)
			(effects
				(font
					(size 1.27 1.27)
					(thickness 0.15)
				)
				(justify left bottom)
				(hide yes)
			)
		)
		(property "Manufacturer" "Walsin"
			(at 264.16 82.55 0)
			(effects
				(font
					(size 1.27 1.27)
					(thickness 0.15)
				)
				(justify left bottom)
				(hide yes)
			)
		)
		(property "License" "Apache-2.0"
			(at 266.7 82.55 0)
			(effects
				(font
					(size 1.27 1.27)
					(thickness 0.15)
				)
				(justify left bottom)
				(hide yes)
			)
		)
		(property "Author" "Antmicro"
			(at 269.24 82.55 0)
			(effects
				(font
					(size 1.27 1.27)
					(thickness 0.15)
				)
				(justify left bottom)
				(hide yes)
			)
		)
		(property "Val" "470p"
			(at 245.872 101.6 90)
			(effects
				(font
					(size 1.27 1.27)
					(thickness 0.15)
				)
				(justify right)
			)
		)
		(property "Voltage" "25V"
			(at 271.78 82.55 0)
			(effects
				(font
					(size 1.27 1.27)
				)
				(justify left bottom)
				(hide yes)
			)
		)
		(property "Dielectric" "X7R"
			(at 274.32 82.55 0)
			(effects
				(font
					(size 1.27 1.27)
				)
				(justify left bottom)
				(hide yes)
			)
		)
		(pin "2"
		)
		(pin "1"
		)
		(instances
			(project "OCuLink to 10GbE adapter"
				(path ""
					(reference "C49")
					(unit 1)
				)
			)
		)
	)
	(symbol
		(lib_id "antmicropower:+1V8")
		(at 59.69 95.25 0)
		(unit 1)
		(exclude_from_sim no)
		(in_bom yes)
		(on_board yes)
		(dnp no)
		(property "Reference" "#PWR067"
			(at 74.93 97.79 0)
			(effects
				(font
					(size 1.27 1.27)
					(thickness 0.15)
				)
				(justify left bottom)
				(hide yes)
			)
		)
		(property "Value" "+1V88"
			(at 59.69 91.44 0)
			(effects
				(font
					(size 1.27 1.27)
					(thickness 0.15)
				)
			)
		)
		(property "Footprint" ""
			(at 74.93 102.87 0)
			(effects
				(font
					(size 1.27 1.27)
					(thickness 0.15)
				)
				(justify left bottom)
				(hide yes)
			)
		)
		(property "Datasheet" ""
			(at 74.93 105.41 0)
			(effects
				(font
					(size 1.27 1.27)
					(thickness 0.15)
				)
				(justify left bottom)
				(hide yes)
			)
		)
		(property "Description" ""
			(at 59.69 95.25 0)
			(effects
				(font
					(size 1.27 1.27)
				)
				(hide yes)
			)
		)
		(property "Author" "Antmicro"
			(at 74.93 100.33 0)
			(effects
				(font
					(size 1.27 1.27)
					(thickness 0.15)
				)
				(justify left bottom)
				(hide yes)
			)
		)
		(property "License" "Apache-2.0"
			(at 74.93 102.87 0)
			(effects
				(font
					(size 1.27 1.27)
					(thickness 0.15)
				)
				(justify left bottom)
				(hide yes)
			)
		)
		(pin "1"
		)
		(instances
			(project "OCuLink to 10GbE adapter"
				(path ""
					(reference "#PWR067")
					(unit 1)
				)
			)
		)
	)
	(symbol
		(lib_id "antmicropower:GND")
		(at 194.31 243.84 0)
		(unit 1)
		(exclude_from_sim no)
		(in_bom yes)
		(on_board yes)
		(dnp no)
		(property "Reference" "#PWR087"
			(at 203.2 246.38 0)
			(effects
				(font
					(size 1.27 1.27)
					(thickness 0.15)
				)
				(justify left bottom)
				(hide yes)
			)
		)
		(property "Value" "GND"
			(at 194.31 247.65 0)
			(effects
				(font
					(size 1.27 1.27)
					(thickness 0.15)
				)
			)
		)
		(property "Footprint" ""
			(at 203.2 251.46 0)
			(effects
				(font
					(size 1.27 1.27)
					(thickness 0.15)
				)
				(justify left bottom)
				(hide yes)
			)
		)
		(property "Datasheet" ""
			(at 203.2 256.54 0)
			(effects
				(font
					(size 1.27 1.27)
					(thickness 0.15)
				)
				(justify left bottom)
				(hide yes)
			)
		)
		(property "Description" ""
			(at 194.31 243.84 0)
			(effects
				(font
					(size 1.27 1.27)
				)
				(hide yes)
			)
		)
		(property "Author" "Antmicro"
			(at 203.2 251.46 0)
			(effects
				(font
					(size 1.27 1.27)
					(thickness 0.15)
				)
				(justify left bottom)
				(hide yes)
			)
		)
		(property "License" "Apache-2.0"
			(at 203.2 254 0)
			(effects
				(font
					(size 1.27 1.27)
					(thickness 0.15)
				)
				(justify left bottom)
				(hide yes)
			)
		)
		(pin "1"
		)
		(instances
			(project "OCuLink to 10GbE adapter"
				(path ""
					(reference "#PWR087")
					(unit 1)
				)
			)
		)
	)
	(symbol
		(lib_id "antmicroCapacitors0402:C_1u_25V_0402")
		(at 185.42 241.3 90)
		(unit 1)
		(exclude_from_sim no)
		(in_bom yes)
		(on_board yes)
		(dnp no)
		(property "Reference" "C66"
			(at 187.452 237.49 90)
			(effects
				(font
					(size 1.27 1.27)
					(thickness 0.15)
				)
				(justify right)
			)
		)
		(property "Value" "C_1u_25V_0402"
			(at 195.58 220.98 0)
			(effects
				(font
					(size 1.27 1.27)
					(thickness 0.15)
				)
				(justify left bottom)
				(hide yes)
			)
		)
		(property "Footprint" "antmicro-footprints:C_0402_1005Metric"
			(at 198.12 220.98 0)
			(effects
				(font
					(size 1.27 1.27)
					(thickness 0.15)
				)
				(justify left bottom)
				(hide yes)
			)
		)
		(property "Datasheet" "https://www.murata.com/products/productdetail?partno=GRM155R61E105KE11%23"
			(at 200.66 220.98 0)
			(effects
				(font
					(size 1.27 1.27)
					(thickness 0.15)
				)
				(justify left bottom)
				(hide yes)
			)
		)
		(property "Description" "SMD Multilayer Ceramic Capacitor, 1 µF, 25 V, 0402 [1005 Metric], ± 10%, X5R, GRM Series"
			(at 185.42 241.3 0)
			(effects
				(font
					(size 1.27 1.27)
				)
				(hide yes)
			)
		)
		(property "MPN" "GRM155R61E105KE11J"
			(at 203.2 220.98 0)
			(effects
				(font
					(size 1.27 1.27)
					(thickness 0.15)
				)
				(justify left bottom)
				(hide yes)
			)
		)
		(property "Manufacturer" "Murata"
			(at 205.74 220.98 0)
			(effects
				(font
					(size 1.27 1.27)
					(thickness 0.15)
				)
				(justify left bottom)
				(hide yes)
			)
		)
		(property "License" "Apache-2.0"
			(at 208.28 220.98 0)
			(effects
				(font
					(size 1.27 1.27)
					(thickness 0.15)
				)
				(justify left bottom)
				(hide yes)
			)
		)
		(property "Author" "Antmicro"
			(at 210.82 220.98 0)
			(effects
				(font
					(size 1.27 1.27)
					(thickness 0.15)
				)
				(justify left bottom)
				(hide yes)
			)
		)
		(property "Val" "1u"
			(at 187.452 240.03 90)
			(effects
				(font
					(size 1.27 1.27)
					(thickness 0.15)
				)
				(justify right)
			)
		)
		(property "Voltage" "25V"
			(at 213.36 220.98 0)
			(effects
				(font
					(size 1.27 1.27)
				)
				(justify left bottom)
				(hide yes)
			)
		)
		(property "Dielectric" "X5R"
			(at 215.9 220.98 0)
			(effects
				(font
					(size 1.27 1.27)
				)
				(justify left bottom)
				(hide yes)
			)
		)
		(pin "1"
		)
		(pin "2"
		)
		(instances
			(project "OCuLink to 10GbE adapter"
				(path ""
					(reference "C66")
					(unit 1)
				)
			)
		)
	)
	(symbol
		(lib_id "antmicroCapacitorsmisc:C_100u_0805")
		(at 154.94 105.41 90)
		(unit 1)
		(exclude_from_sim no)
		(in_bom yes)
		(on_board yes)
		(dnp no)
		(property "Reference" "C55"
			(at 156.972 101.6 90)
			(effects
				(font
					(size 1.27 1.27)
					(thickness 0.15)
				)
				(justify right)
			)
		)
		(property "Value" "C_100u_0805"
			(at 165.1 85.09 0)
			(effects
				(font
					(size 1.27 1.27)
					(thickness 0.15)
				)
				(justify left bottom)
				(hide yes)
			)
		)
		(property "Footprint" "antmicro-footprints:C_0805_2012Metric"
			(at 167.64 85.09 0)
			(effects
				(font
					(size 1.27 1.27)
					(thickness 0.15)
				)
				(justify left bottom)
				(hide yes)
			)
		)
		(property "Datasheet" "https://www.murata.com/products/productdetail?partno=GRM21BR60J107ME15%23"
			(at 170.18 85.09 0)
			(effects
				(font
					(size 1.27 1.27)
					(thickness 0.15)
				)
				(justify left bottom)
				(hide yes)
			)
		)
		(property "Description" "SMD Multilayer Ceramic Capacitor, 100 µF, 6.3 V, 0805 [2012 Metric], ± 20%, X5R, GRM Series"
			(at 154.94 105.41 0)
			(effects
				(font
					(size 1.27 1.27)
				)
				(hide yes)
			)
		)
		(property "MPN" "GRM21BR60J107ME15L"
			(at 172.72 85.09 0)
			(effects
				(font
					(size 1.27 1.27)
					(thickness 0.15)
				)
				(justify left bottom)
				(hide yes)
			)
		)
		(property "Manufacturer" "Murata"
			(at 175.26 85.09 0)
			(effects
				(font
					(size 1.27 1.27)
					(thickness 0.15)
				)
				(justify left bottom)
				(hide yes)
			)
		)
		(property "License" "Apache-2.0"
			(at 177.8 85.09 0)
			(effects
				(font
					(size 1.27 1.27)
					(thickness 0.15)
				)
				(justify left bottom)
				(hide yes)
			)
		)
		(property "Author" "Antmicro"
			(at 180.34 85.09 0)
			(effects
				(font
					(size 1.27 1.27)
					(thickness 0.15)
				)
				(justify left bottom)
				(hide yes)
			)
		)
		(property "Val" "100u"
			(at 156.972 104.14 90)
			(effects
				(font
					(size 1.27 1.27)
					(thickness 0.15)
				)
				(justify right)
			)
		)
		(property "Voltage" ""
			(at 182.88 85.09 0)
			(effects
				(font
					(size 1.27 1.27)
				)
				(justify left bottom)
				(hide yes)
			)
		)
		(property "Dielectric" ""
			(at 185.42 85.09 0)
			(effects
				(font
					(size 1.27 1.27)
				)
				(justify left bottom)
				(hide yes)
			)
		)
		(property "Public" "False"
			(at 187.96 85.09 0)
			(effects
				(font
					(size 1.27 1.27)
				)
				(justify left bottom)
				(hide yes)
			)
		)
		(pin "1"
		)
		(pin "2"
		)
		(instances
			(project ""
				(path ""
					(reference "C55")
					(unit 1)
				)
			)
		)
	)
	(symbol
		(lib_id "antmicropower:PWR_FLAG")
		(at 106.68 96.52 0)
		(unit 1)
		(exclude_from_sim no)
		(in_bom yes)
		(on_board yes)
		(dnp no)
		(fields_autoplaced yes)
		(property "Reference" "#FLG010"
			(at 106.68 94.615 0)
			(effects
				(font
					(size 1.27 1.27)
				)
				(hide yes)
			)
		)
		(property "Value" "PWR_FLAG"
			(at 106.68 91.44 0)
			(effects
				(font
					(size 1.27 1.27)
				)
			)
		)
		(property "Footprint" ""
			(at 106.68 96.52 0)
			(effects
				(font
					(size 1.27 1.27)
				)
				(hide yes)
			)
		)
		(property "Datasheet" ""
			(at 106.68 96.52 0)
			(effects
				(font
					(size 1.27 1.27)
				)
				(hide yes)
			)
		)
		(property "Description" ""
			(at 106.68 99.06 0)
			(effects
				(font
					(size 1.27 1.27)
				)
				(justify left bottom)
				(hide yes)
			)
		)
		(pin "1"
		)
		(instances
			(project ""
				(path ""
					(reference "#FLG010")
					(unit 1)
				)
			)
		)
	)
	(symbol
		(lib_id "antmicroCapacitorsmisc:C_220u_1206_6V3")
		(at 95.25 105.41 90)
		(unit 1)
		(exclude_from_sim no)
		(in_bom yes)
		(on_board yes)
		(dnp no)
		(property "Reference" "C54"
			(at 97.282 101.6 90)
			(effects
				(font
					(size 1.27 1.27)
					(thickness 0.15)
				)
				(justify right)
			)
		)
		(property "Value" "C_220u_1206_6V3"
			(at 105.41 85.09 0)
			(effects
				(font
					(size 1.27 1.27)
					(thickness 0.15)
				)
				(justify left bottom)
				(hide yes)
			)
		)
		(property "Footprint" "antmicro-footprints:C_1206_3216Metric"
			(at 107.95 85.09 0)
			(effects
				(font
					(size 1.27 1.27)
					(thickness 0.15)
				)
				(justify left bottom)
				(hide yes)
			)
		)
		(property "Datasheet" "https://www.murata.com/products/productdetail?partno=GRM31CR60J227ME11%23"
			(at 110.49 85.09 0)
			(effects
				(font
					(size 1.27 1.27)
					(thickness 0.15)
				)
				(justify left bottom)
				(hide yes)
			)
		)
		(property "Description" "SMD Multilayer Ceramic Capacitor, 220 µF, 6.3 V, 1206 [3216 Metric], ± 20%, X5R, GRM Series"
			(at 95.25 105.41 0)
			(effects
				(font
					(size 1.27 1.27)
				)
				(hide yes)
			)
		)
		(property "MPN" "GRM31CR60J227ME11L"
			(at 113.03 85.09 0)
			(effects
				(font
					(size 1.27 1.27)
					(thickness 0.15)
				)
				(justify left bottom)
				(hide yes)
			)
		)
		(property "Manufacturer" "Murata"
			(at 115.57 85.09 0)
			(effects
				(font
					(size 1.27 1.27)
					(thickness 0.15)
				)
				(justify left bottom)
				(hide yes)
			)
		)
		(property "License" "Apache-2.0"
			(at 118.11 85.09 0)
			(effects
				(font
					(size 1.27 1.27)
					(thickness 0.15)
				)
				(justify left bottom)
				(hide yes)
			)
		)
		(property "Author" "Antmicro"
			(at 120.65 85.09 0)
			(effects
				(font
					(size 1.27 1.27)
					(thickness 0.15)
				)
				(justify left bottom)
				(hide yes)
			)
		)
		(property "Val" "220u"
			(at 97.282 104.14 90)
			(effects
				(font
					(size 1.27 1.27)
					(thickness 0.15)
				)
				(justify right)
			)
		)
		(property "Voltage" ""
			(at 123.19 85.09 0)
			(effects
				(font
					(size 1.27 1.27)
				)
				(justify left bottom)
				(hide yes)
			)
		)
		(property "Dielectric" ""
			(at 125.73 85.09 0)
			(effects
				(font
					(size 1.27 1.27)
				)
				(justify left bottom)
				(hide yes)
			)
		)
		(property "Public" "False"
			(at 128.27 85.09 0)
			(effects
				(font
					(size 1.27 1.27)
				)
				(justify left bottom)
				(hide yes)
			)
		)
		(pin "1"
		)
		(pin "2"
		)
		(instances
			(project ""
				(path ""
					(reference "C54")
					(unit 1)
				)
			)
		)
	)
	(symbol
		(lib_id "antmicropower:GND")
		(at 368.3 124.46 0)
		(unit 1)
		(exclude_from_sim no)
		(in_bom yes)
		(on_board yes)
		(dnp no)
		(property "Reference" "#PWR080"
			(at 377.19 127 0)
			(effects
				(font
					(size 1.27 1.27)
					(thickness 0.15)
				)
				(justify left bottom)
				(hide yes)
			)
		)
		(property "Value" "GND"
			(at 368.3 128.27 0)
			(effects
				(font
					(size 1.27 1.27)
					(thickness 0.15)
				)
			)
		)
		(property "Footprint" ""
			(at 377.19 132.08 0)
			(effects
				(font
					(size 1.27 1.27)
					(thickness 0.15)
				)
				(justify left bottom)
				(hide yes)
			)
		)
		(property "Datasheet" ""
			(at 377.19 137.16 0)
			(effects
				(font
					(size 1.27 1.27)
					(thickness 0.15)
				)
				(justify left bottom)
				(hide yes)
			)
		)
		(property "Description" ""
			(at 368.3 124.46 0)
			(effects
				(font
					(size 1.27 1.27)
				)
				(hide yes)
			)
		)
		(property "Author" "Antmicro"
			(at 377.19 132.08 0)
			(effects
				(font
					(size 1.27 1.27)
					(thickness 0.15)
				)
				(justify left bottom)
				(hide yes)
			)
		)
		(property "License" "Apache-2.0"
			(at 377.19 134.62 0)
			(effects
				(font
					(size 1.27 1.27)
					(thickness 0.15)
				)
				(justify left bottom)
				(hide yes)
			)
		)
		(pin "1"
		)
		(instances
			(project "OCuLink to 10GbE adapter"
				(path ""
					(reference "#PWR080")
					(unit 1)
				)
			)
		)
	)
	(symbol
		(lib_id "antmicroResistors0402:R_220R_0402")
		(at 259.08 82.55 0)
		(unit 1)
		(exclude_from_sim no)
		(in_bom yes)
		(on_board yes)
		(dnp no)
		(property "Reference" "R36"
			(at 259.08 81.28 0)
			(effects
				(font
					(size 1.27 1.27)
					(thickness 0.15)
				)
				(justify right)
			)
		)
		(property "Value" "R_220R_0402"
			(at 279.4 95.25 0)
			(effects
				(font
					(size 1.27 1.27)
					(thickness 0.15)
				)
				(justify left bottom)
				(hide yes)
			)
		)
		(property "Footprint" "antmicro-footprints:R_0402_1005Metric"
			(at 279.4 97.79 0)
			(effects
				(font
					(size 1.27 1.27)
					(thickness 0.15)
				)
				(justify left bottom)
				(hide yes)
			)
		)
		(property "Datasheet" "https://www.bourns.com/docs/product-datasheets/cr.pdf"
			(at 279.4 100.33 0)
			(effects
				(font
					(size 1.27 1.27)
					(thickness 0.15)
				)
				(justify left bottom)
				(hide yes)
			)
		)
		(property "Description" "SMD Chip Resistor, 220 ohm, ± 1%, 62.5 mW, 0402 [1005 Metric], Thick Film, General Purpose"
			(at 259.08 82.55 0)
			(effects
				(font
					(size 1.27 1.27)
				)
				(hide yes)
			)
		)
		(property "MPN" "CR0402-FX-2200GLF"
			(at 279.4 102.87 0)
			(effects
				(font
					(size 1.27 1.27)
					(thickness 0.15)
				)
				(justify left bottom)
				(hide yes)
			)
		)
		(property "Manufacturer" "Bourns"
			(at 279.4 105.41 0)
			(effects
				(font
					(size 1.27 1.27)
					(thickness 0.15)
				)
				(justify left bottom)
				(hide yes)
			)
		)
		(property "License" "Apache-2.0"
			(at 279.4 107.95 0)
			(effects
				(font
					(size 1.27 1.27)
					(thickness 0.15)
				)
				(justify left bottom)
				(hide yes)
			)
		)
		(property "Author" "Antmicro"
			(at 279.4 110.49 0)
			(effects
				(font
					(size 1.27 1.27)
					(thickness 0.15)
				)
				(justify left bottom)
				(hide yes)
			)
		)
		(property "Val" "220R"
			(at 264.16 81.28 0)
			(effects
				(font
					(size 1.27 1.27)
					(thickness 0.15)
				)
				(justify left)
			)
		)
		(property "Tolerance" "1%"
			(at 279.4 92.71 0)
			(effects
				(font
					(size 1.27 1.27)
				)
				(justify left bottom)
				(hide yes)
			)
		)
		(pin "1"
		)
		(pin "2"
		)
		(instances
			(project ""
				(path ""
					(reference "R36")
					(unit 1)
				)
			)
		)
	)
	(symbol
		(lib_id "antmicropower:+1V8")
		(at 142.24 95.25 0)
		(unit 1)
		(exclude_from_sim no)
		(in_bom yes)
		(on_board yes)
		(dnp no)
		(property "Reference" "#PWR069"
			(at 157.48 97.79 0)
			(effects
				(font
					(size 1.27 1.27)
					(thickness 0.15)
				)
				(justify left bottom)
				(hide yes)
			)
		)
		(property "Value" "+1V88_CT"
			(at 142.24 91.44 0)
			(effects
				(font
					(size 1.27 1.27)
					(thickness 0.15)
				)
			)
		)
		(property "Footprint" ""
			(at 157.48 102.87 0)
			(effects
				(font
					(size 1.27 1.27)
					(thickness 0.15)
				)
				(justify left bottom)
				(hide yes)
			)
		)
		(property "Datasheet" ""
			(at 157.48 105.41 0)
			(effects
				(font
					(size 1.27 1.27)
					(thickness 0.15)
				)
				(justify left bottom)
				(hide yes)
			)
		)
		(property "Description" ""
			(at 142.24 95.25 0)
			(effects
				(font
					(size 1.27 1.27)
				)
				(hide yes)
			)
		)
		(property "Author" "Antmicro"
			(at 157.48 100.33 0)
			(effects
				(font
					(size 1.27 1.27)
					(thickness 0.15)
				)
				(justify left bottom)
				(hide yes)
			)
		)
		(property "License" "Apache-2.0"
			(at 157.48 102.87 0)
			(effects
				(font
					(size 1.27 1.27)
					(thickness 0.15)
				)
				(justify left bottom)
				(hide yes)
			)
		)
		(pin "1"
		)
		(instances
			(project "OCuLink to 10GbE adapter"
				(path ""
					(reference "#PWR069")
					(unit 1)
				)
			)
		)
	)
	(symbol
		(lib_id "antmicropower:+3V3")
		(at 228.6 213.36 0)
		(unit 1)
		(exclude_from_sim no)
		(in_bom yes)
		(on_board yes)
		(dnp no)
		(property "Reference" "#PWR081"
			(at 243.84 213.36 0)
			(effects
				(font
					(size 1.27 1.27)
					(thickness 0.15)
				)
				(justify left bottom)
				(hide yes)
			)
		)
		(property "Value" "+3V3"
			(at 228.6 209.55 0)
			(effects
				(font
					(size 1.27 1.27)
					(thickness 0.15)
				)
			)
		)
		(property "Footprint" ""
			(at 243.84 220.98 0)
			(effects
				(font
					(size 1.27 1.27)
					(thickness 0.15)
				)
				(justify left bottom)
				(hide yes)
			)
		)
		(property "Datasheet" ""
			(at 243.84 223.52 0)
			(effects
				(font
					(size 1.27 1.27)
					(thickness 0.15)
				)
				(justify left bottom)
				(hide yes)
			)
		)
		(property "Description" ""
			(at 228.6 213.36 0)
			(effects
				(font
					(size 1.27 1.27)
				)
				(hide yes)
			)
		)
		(property "Author" "Antmicro"
			(at 243.84 215.9 0)
			(effects
				(font
					(size 1.27 1.27)
					(thickness 0.15)
				)
				(justify left bottom)
				(hide yes)
			)
		)
		(property "License" "Apache-2.0"
			(at 243.84 218.44 0)
			(effects
				(font
					(size 1.27 1.27)
					(thickness 0.15)
				)
				(justify left bottom)
				(hide yes)
			)
		)
		(pin "1"
		)
		(instances
			(project "OCuLink to 10GbE adapter"
				(path ""
					(reference "#PWR081")
					(unit 1)
				)
			)
		)
	)
	(symbol
		(lib_id "antmicroCapacitors0402:C_1u_25V_0402")
		(at 86.36 105.41 90)
		(unit 1)
		(exclude_from_sim no)
		(in_bom yes)
		(on_board yes)
		(dnp no)
		(property "Reference" "C53"
			(at 88.392 101.6 90)
			(effects
				(font
					(size 1.27 1.27)
					(thickness 0.15)
				)
				(justify right)
			)
		)
		(property "Value" "C_1u_25V_0402"
			(at 96.52 85.09 0)
			(effects
				(font
					(size 1.27 1.27)
					(thickness 0.15)
				)
				(justify left bottom)
				(hide yes)
			)
		)
		(property "Footprint" "antmicro-footprints:C_0402_1005Metric"
			(at 99.06 85.09 0)
			(effects
				(font
					(size 1.27 1.27)
					(thickness 0.15)
				)
				(justify left bottom)
				(hide yes)
			)
		)
		(property "Datasheet" "https://www.murata.com/products/productdetail?partno=GRM155R61E105KE11%23"
			(at 101.6 85.09 0)
			(effects
				(font
					(size 1.27 1.27)
					(thickness 0.15)
				)
				(justify left bottom)
				(hide yes)
			)
		)
		(property "Description" "SMD Multilayer Ceramic Capacitor, 1 µF, 25 V, 0402 [1005 Metric], ± 10%, X5R, GRM Series"
			(at 86.36 105.41 0)
			(effects
				(font
					(size 1.27 1.27)
				)
				(hide yes)
			)
		)
		(property "MPN" "GRM155R61E105KE11J"
			(at 104.14 85.09 0)
			(effects
				(font
					(size 1.27 1.27)
					(thickness 0.15)
				)
				(justify left bottom)
				(hide yes)
			)
		)
		(property "Manufacturer" "Murata"
			(at 106.68 85.09 0)
			(effects
				(font
					(size 1.27 1.27)
					(thickness 0.15)
				)
				(justify left bottom)
				(hide yes)
			)
		)
		(property "License" "Apache-2.0"
			(at 109.22 85.09 0)
			(effects
				(font
					(size 1.27 1.27)
					(thickness 0.15)
				)
				(justify left bottom)
				(hide yes)
			)
		)
		(property "Author" "Antmicro"
			(at 111.76 85.09 0)
			(effects
				(font
					(size 1.27 1.27)
					(thickness 0.15)
				)
				(justify left bottom)
				(hide yes)
			)
		)
		(property "Val" "1u"
			(at 88.392 104.14 90)
			(effects
				(font
					(size 1.27 1.27)
					(thickness 0.15)
				)
				(justify right)
			)
		)
		(property "Voltage" "25V"
			(at 114.3 85.09 0)
			(effects
				(font
					(size 1.27 1.27)
				)
				(justify left bottom)
				(hide yes)
			)
		)
		(property "Dielectric" "X5R"
			(at 116.84 85.09 0)
			(effects
				(font
					(size 1.27 1.27)
				)
				(justify left bottom)
				(hide yes)
			)
		)
		(pin "1"
		)
		(pin "2"
		)
		(instances
			(project "OCuLink to 10GbE adapter"
				(path ""
					(reference "C53")
					(unit 1)
				)
			)
		)
	)
	(symbol
		(lib_id "antmicropower:+1V8")
		(at 142.24 231.14 0)
		(unit 1)
		(exclude_from_sim no)
		(in_bom yes)
		(on_board yes)
		(dnp no)
		(property "Reference" "#PWR082"
			(at 157.48 233.68 0)
			(effects
				(font
					(size 1.27 1.27)
					(thickness 0.15)
				)
				(justify left bottom)
				(hide yes)
			)
		)
		(property "Value" "+1V88_CT"
			(at 142.24 227.33 0)
			(effects
				(font
					(size 1.27 1.27)
					(thickness 0.15)
				)
			)
		)
		(property "Footprint" ""
			(at 157.48 238.76 0)
			(effects
				(font
					(size 1.27 1.27)
					(thickness 0.15)
				)
				(justify left bottom)
				(hide yes)
			)
		)
		(property "Datasheet" ""
			(at 157.48 241.3 0)
			(effects
				(font
					(size 1.27 1.27)
					(thickness 0.15)
				)
				(justify left bottom)
				(hide yes)
			)
		)
		(property "Description" ""
			(at 142.24 231.14 0)
			(effects
				(font
					(size 1.27 1.27)
				)
				(hide yes)
			)
		)
		(property "Author" "Antmicro"
			(at 157.48 236.22 0)
			(effects
				(font
					(size 1.27 1.27)
					(thickness 0.15)
				)
				(justify left bottom)
				(hide yes)
			)
		)
		(property "License" "Apache-2.0"
			(at 157.48 238.76 0)
			(effects
				(font
					(size 1.27 1.27)
					(thickness 0.15)
				)
				(justify left bottom)
				(hide yes)
			)
		)
		(pin "1"
		)
		(instances
			(project "OCuLink to 10GbE adapter"
				(path ""
					(reference "#PWR082")
					(unit 1)
				)
			)
		)
	)
	(symbol
		(lib_id "antmicroModularConnectorsJacksWithMagnetics:Bus_RJ45_JTH-0024NL")
		(at 204.47 62.23 0)
		(unit 1)
		(exclude_from_sim no)
		(in_bom yes)
		(on_board yes)
		(dnp no)
		(fields_autoplaced yes)
		(property "Reference" "J3"
			(at 215.265 54.61 0)
			(effects
				(font
					(size 1.27 1.27)
					(thickness 0.15)
				)
			)
		)
		(property "Value" "Bus_RJ45_JTH-0024NL"
			(at 240.03 67.31 0)
			(effects
				(font
					(size 1.27 1.27)
					(thickness 0.15)
				)
				(justify left bottom)
				(hide yes)
			)
		)
		(property "Footprint" "antmicro-footprints:RJ45_JTH-0024NL"
			(at 240.03 69.85 0)
			(effects
				(font
					(size 1.27 1.27)
					(thickness 0.15)
				)
				(justify left bottom)
				(hide yes)
			)
		)
		(property "Datasheet" "https://www.mouser.com/datasheet/2/447/JTH_0024NL-3072047.pdf"
			(at 240.03 72.39 0)
			(effects
				(font
					(size 1.27 1.27)
					(thickness 0.15)
				)
				(justify left bottom)
				(hide yes)
			)
		)
		(property "Description" "Modular Connectors / Ethernet Connectors 1X1 TAB DOWN W/LED'S ETHERNET (NON PoE)"
			(at 204.47 62.23 0)
			(effects
				(font
					(size 1.27 1.27)
				)
				(hide yes)
			)
		)
		(property "MPN" "JTH-0024NL"
			(at 215.265 57.15 0)
			(effects
				(font
					(size 1.27 1.27)
					(thickness 0.15)
				)
			)
		)
		(property "Manufacturer" "Pulse Electronics"
			(at 240.03 77.47 0)
			(effects
				(font
					(size 1.27 1.27)
					(thickness 0.15)
				)
				(justify left bottom)
				(hide yes)
			)
		)
		(property "Author" "Antmicro"
			(at 240.03 80.01 0)
			(effects
				(font
					(size 1.27 1.27)
					(thickness 0.15)
				)
				(justify left bottom)
				(hide yes)
			)
		)
		(property "License" "Apache-2.0"
			(at 240.03 82.55 0)
			(effects
				(font
					(size 1.27 1.27)
					(thickness 0.15)
				)
				(justify left bottom)
				(hide yes)
			)
		)
		(pin "8"
		)
		(pin "14"
		)
		(pin "9"
		)
		(pin "11"
		)
		(pin "10"
		)
		(pin "SH"
		)
		(pin "13"
		)
		(pin "17"
		)
		(pin "6"
		)
		(pin "12"
		)
		(pin "1"
		)
		(pin "2"
		)
		(pin "4"
		)
		(pin "5"
		)
		(pin "3"
		)
		(pin "7"
		)
		(pin "15"
		)
		(pin "16"
		)
		(instances
			(project ""
				(path ""
					(reference "J3")
					(unit 1)
				)
			)
		)
	)
	(symbol
		(lib_id "antmicropower:GND")
		(at 185.42 243.84 0)
		(unit 1)
		(exclude_from_sim no)
		(in_bom yes)
		(on_board yes)
		(dnp no)
		(property "Reference" "#PWR086"
			(at 194.31 246.38 0)
			(effects
				(font
					(size 1.27 1.27)
					(thickness 0.15)
				)
				(justify left bottom)
				(hide yes)
			)
		)
		(property "Value" "GND"
			(at 185.42 247.65 0)
			(effects
				(font
					(size 1.27 1.27)
					(thickness 0.15)
				)
			)
		)
		(property "Footprint" ""
			(at 194.31 251.46 0)
			(effects
				(font
					(size 1.27 1.27)
					(thickness 0.15)
				)
				(justify left bottom)
				(hide yes)
			)
		)
		(property "Datasheet" ""
			(at 194.31 256.54 0)
			(effects
				(font
					(size 1.27 1.27)
					(thickness 0.15)
				)
				(justify left bottom)
				(hide yes)
			)
		)
		(property "Description" ""
			(at 185.42 243.84 0)
			(effects
				(font
					(size 1.27 1.27)
				)
				(hide yes)
			)
		)
		(property "Author" "Antmicro"
			(at 194.31 251.46 0)
			(effects
				(font
					(size 1.27 1.27)
					(thickness 0.15)
				)
				(justify left bottom)
				(hide yes)
			)
		)
		(property "License" "Apache-2.0"
			(at 194.31 254 0)
			(effects
				(font
					(size 1.27 1.27)
					(thickness 0.15)
				)
				(justify left bottom)
				(hide yes)
			)
		)
		(pin "1"
		)
		(instances
			(project "OCuLink to 10GbE adapter"
				(path ""
					(reference "#PWR086")
					(unit 1)
				)
			)
		)
	)
	(symbol
		(lib_id "antmicropower:GND")
		(at 154.94 107.95 0)
		(unit 1)
		(exclude_from_sim no)
		(in_bom yes)
		(on_board yes)
		(dnp no)
		(property "Reference" "#PWR074"
			(at 163.83 110.49 0)
			(effects
				(font
					(size 1.27 1.27)
					(thickness 0.15)
				)
				(justify left bottom)
				(hide yes)
			)
		)
		(property "Value" "GND"
			(at 154.94 111.76 0)
			(effects
				(font
					(size 1.27 1.27)
					(thickness 0.15)
				)
			)
		)
		(property "Footprint" ""
			(at 163.83 115.57 0)
			(effects
				(font
					(size 1.27 1.27)
					(thickness 0.15)
				)
				(justify left bottom)
				(hide yes)
			)
		)
		(property "Datasheet" ""
			(at 163.83 120.65 0)
			(effects
				(font
					(size 1.27 1.27)
					(thickness 0.15)
				)
				(justify left bottom)
				(hide yes)
			)
		)
		(property "Description" ""
			(at 154.94 107.95 0)
			(effects
				(font
					(size 1.27 1.27)
				)
				(hide yes)
			)
		)
		(property "Author" "Antmicro"
			(at 163.83 115.57 0)
			(effects
				(font
					(size 1.27 1.27)
					(thickness 0.15)
				)
				(justify left bottom)
				(hide yes)
			)
		)
		(property "License" "Apache-2.0"
			(at 163.83 118.11 0)
			(effects
				(font
					(size 1.27 1.27)
					(thickness 0.15)
				)
				(justify left bottom)
				(hide yes)
			)
		)
		(pin "1"
		)
		(instances
			(project "OCuLink to 10GbE adapter"
				(path ""
					(reference "#PWR074")
					(unit 1)
				)
			)
		)
	)
	(symbol
		(lib_id "antmicropower:+3V3")
		(at 228.6 77.47 0)
		(unit 1)
		(exclude_from_sim no)
		(in_bom yes)
		(on_board yes)
		(dnp no)
		(property "Reference" "#PWR066"
			(at 243.84 77.47 0)
			(effects
				(font
					(size 1.27 1.27)
					(thickness 0.15)
				)
				(justify left bottom)
				(hide yes)
			)
		)
		(property "Value" "+3V3"
			(at 228.6 73.66 0)
			(effects
				(font
					(size 1.27 1.27)
					(thickness 0.15)
				)
			)
		)
		(property "Footprint" ""
			(at 243.84 85.09 0)
			(effects
				(font
					(size 1.27 1.27)
					(thickness 0.15)
				)
				(justify left bottom)
				(hide yes)
			)
		)
		(property "Datasheet" ""
			(at 243.84 87.63 0)
			(effects
				(font
					(size 1.27 1.27)
					(thickness 0.15)
				)
				(justify left bottom)
				(hide yes)
			)
		)
		(property "Description" ""
			(at 228.6 77.47 0)
			(effects
				(font
					(size 1.27 1.27)
				)
				(hide yes)
			)
		)
		(property "Author" "Antmicro"
			(at 243.84 80.01 0)
			(effects
				(font
					(size 1.27 1.27)
					(thickness 0.15)
				)
				(justify left bottom)
				(hide yes)
			)
		)
		(property "License" "Apache-2.0"
			(at 243.84 82.55 0)
			(effects
				(font
					(size 1.27 1.27)
					(thickness 0.15)
				)
				(justify left bottom)
				(hide yes)
			)
		)
		(pin "1"
		)
		(instances
			(project "OCuLink to 10GbE adapter"
				(path ""
					(reference "#PWR066")
					(unit 1)
				)
			)
		)
	)
	(symbol
		(lib_id "antmicroCapacitors0603:C_22u_16V_0603")
		(at 71.12 105.41 90)
		(unit 1)
		(exclude_from_sim no)
		(in_bom yes)
		(on_board yes)
		(dnp no)
		(property "Reference" "C52"
			(at 73.152 101.6 90)
			(effects
				(font
					(size 1.27 1.27)
					(thickness 0.15)
				)
				(justify right)
			)
		)
		(property "Value" "C_22u_16V_0603"
			(at 81.28 85.09 0)
			(effects
				(font
					(size 1.27 1.27)
					(thickness 0.15)
				)
				(justify left bottom)
				(hide yes)
			)
		)
		(property "Footprint" "antmicro-footprints:C_0603_1608Metric_EIA"
			(at 83.82 85.09 0)
			(effects
				(font
					(size 1.27 1.27)
					(thickness 0.15)
				)
				(justify left bottom)
				(hide yes)
			)
		)
		(property "Datasheet" "https://product.samsungsem.com/mlcc/CL10A226MO7JZN.do"
			(at 86.36 85.09 0)
			(effects
				(font
					(size 1.27 1.27)
					(thickness 0.15)
				)
				(justify left bottom)
				(hide yes)
			)
		)
		(property "Description" "SMD Multilayer Ceramic Capacitor"
			(at 71.12 105.41 0)
			(effects
				(font
					(size 1.27 1.27)
				)
				(hide yes)
			)
		)
		(property "MPN" "CL10A226MO7JZNC"
			(at 88.9 85.09 0)
			(effects
				(font
					(size 1.27 1.27)
					(thickness 0.15)
				)
				(justify left bottom)
				(hide yes)
			)
		)
		(property "Manufacturer" "Samsung Electro-Mechanics"
			(at 91.44 85.09 0)
			(effects
				(font
					(size 1.27 1.27)
					(thickness 0.15)
				)
				(justify left bottom)
				(hide yes)
			)
		)
		(property "License" "Apache-2.0"
			(at 93.98 85.09 0)
			(effects
				(font
					(size 1.27 1.27)
					(thickness 0.15)
				)
				(justify left bottom)
				(hide yes)
			)
		)
		(property "Author" "Antmicro"
			(at 96.52 85.09 0)
			(effects
				(font
					(size 1.27 1.27)
					(thickness 0.15)
				)
				(justify left bottom)
				(hide yes)
			)
		)
		(property "Val" "22u"
			(at 73.152 104.14 90)
			(effects
				(font
					(size 1.27 1.27)
					(thickness 0.15)
				)
				(justify right)
			)
		)
		(property "Voltage" "16V"
			(at 99.06 85.09 0)
			(effects
				(font
					(size 1.27 1.27)
				)
				(justify left bottom)
				(hide yes)
			)
		)
		(property "Dielectric" ""
			(at 101.6 85.09 0)
			(effects
				(font
					(size 1.27 1.27)
				)
				(justify left bottom)
				(hide yes)
			)
		)
		(pin "1"
		)
		(pin "2"
		)
		(instances
			(project ""
				(path ""
					(reference "C52")
					(unit 1)
				)
			)
		)
	)
	(symbol
		(lib_id "antmicropower:GND")
		(at 228.6 243.84 0)
		(unit 1)
		(exclude_from_sim no)
		(in_bom yes)
		(on_board yes)
		(dnp no)
		(property "Reference" "#PWR088"
			(at 237.49 246.38 0)
			(effects
				(font
					(size 1.27 1.27)
					(thickness 0.15)
				)
				(justify left bottom)
				(hide yes)
			)
		)
		(property "Value" "GND"
			(at 228.6 247.65 0)
			(effects
				(font
					(size 1.27 1.27)
					(thickness 0.15)
				)
			)
		)
		(property "Footprint" ""
			(at 237.49 251.46 0)
			(effects
				(font
					(size 1.27 1.27)
					(thickness 0.15)
				)
				(justify left bottom)
				(hide yes)
			)
		)
		(property "Datasheet" ""
			(at 237.49 256.54 0)
			(effects
				(font
					(size 1.27 1.27)
					(thickness 0.15)
				)
				(justify left bottom)
				(hide yes)
			)
		)
		(property "Description" ""
			(at 228.6 243.84 0)
			(effects
				(font
					(size 1.27 1.27)
				)
				(hide yes)
			)
		)
		(property "Author" "Antmicro"
			(at 237.49 251.46 0)
			(effects
				(font
					(size 1.27 1.27)
					(thickness 0.15)
				)
				(justify left bottom)
				(hide yes)
			)
		)
		(property "License" "Apache-2.0"
			(at 237.49 254 0)
			(effects
				(font
					(size 1.27 1.27)
					(thickness 0.15)
				)
				(justify left bottom)
				(hide yes)
			)
		)
		(pin "1"
		)
		(instances
			(project "OCuLink to 10GbE adapter"
				(path ""
					(reference "#PWR088")
					(unit 1)
				)
			)
		)
	)
	(symbol
		(lib_id "antmicroCapacitors0402:C_470p_0402")
		(at 254 102.87 90)
		(unit 1)
		(exclude_from_sim no)
		(in_bom yes)
		(on_board yes)
		(dnp no)
		(property "Reference" "C50"
			(at 256.032 99.06 90)
			(effects
				(font
					(size 1.27 1.27)
					(thickness 0.15)
				)
				(justify right)
			)
		)
		(property "Value" "C_470p_0402"
			(at 264.16 82.55 0)
			(effects
				(font
					(size 1.27 1.27)
					(thickness 0.15)
				)
				(justify left bottom)
				(hide yes)
			)
		)
		(property "Footprint" "antmicro-footprints:C_0402_1005Metric"
			(at 266.7 82.55 0)
			(effects
				(font
					(size 1.27 1.27)
					(thickness 0.15)
				)
				(justify left bottom)
				(hide yes)
			)
		)
		(property "Datasheet" "https://www.passivecomponent.com/wp-content/uploads/datasheet/WTC_MLCC_General_Purpose.pdf"
			(at 269.24 82.55 0)
			(effects
				(font
					(size 1.27 1.27)
					(thickness 0.15)
				)
				(justify left bottom)
				(hide yes)
			)
		)
		(property "Description" "SMD Multilayer Ceramic Capacitor, General Purpose, 470 pF, 25 V, 0402 [1005 Metric], ± 10%, X7R"
			(at 254 102.87 0)
			(effects
				(font
					(size 1.27 1.27)
				)
				(hide yes)
			)
		)
		(property "MPN" "0402B471K250CT"
			(at 271.78 82.55 0)
			(effects
				(font
					(size 1.27 1.27)
					(thickness 0.15)
				)
				(justify left bottom)
				(hide yes)
			)
		)
		(property "Manufacturer" "Walsin"
			(at 274.32 82.55 0)
			(effects
				(font
					(size 1.27 1.27)
					(thickness 0.15)
				)
				(justify left bottom)
				(hide yes)
			)
		)
		(property "License" "Apache-2.0"
			(at 276.86 82.55 0)
			(effects
				(font
					(size 1.27 1.27)
					(thickness 0.15)
				)
				(justify left bottom)
				(hide yes)
			)
		)
		(property "Author" "Antmicro"
			(at 279.4 82.55 0)
			(effects
				(font
					(size 1.27 1.27)
					(thickness 0.15)
				)
				(justify left bottom)
				(hide yes)
			)
		)
		(property "Val" "470p"
			(at 256.032 101.6 90)
			(effects
				(font
					(size 1.27 1.27)
					(thickness 0.15)
				)
				(justify right)
			)
		)
		(property "Voltage" "25V"
			(at 281.94 82.55 0)
			(effects
				(font
					(size 1.27 1.27)
				)
				(justify left bottom)
				(hide yes)
			)
		)
		(property "Dielectric" "X7R"
			(at 284.48 82.55 0)
			(effects
				(font
					(size 1.27 1.27)
				)
				(justify left bottom)
				(hide yes)
			)
		)
		(pin "2"
		)
		(pin "1"
		)
		(instances
			(project "OCuLink to 10GbE adapter"
				(path ""
					(reference "C50")
					(unit 1)
				)
			)
		)
	)
	(symbol
		(lib_id "antmicropower:GND")
		(at 154.94 243.84 0)
		(unit 1)
		(exclude_from_sim no)
		(in_bom yes)
		(on_board yes)
		(dnp no)
		(property "Reference" "#PWR083"
			(at 163.83 246.38 0)
			(effects
				(font
					(size 1.27 1.27)
					(thickness 0.15)
				)
				(justify left bottom)
				(hide yes)
			)
		)
		(property "Value" "GND"
			(at 154.94 247.65 0)
			(effects
				(font
					(size 1.27 1.27)
					(thickness 0.15)
				)
			)
		)
		(property "Footprint" ""
			(at 163.83 251.46 0)
			(effects
				(font
					(size 1.27 1.27)
					(thickness 0.15)
				)
				(justify left bottom)
				(hide yes)
			)
		)
		(property "Datasheet" ""
			(at 163.83 256.54 0)
			(effects
				(font
					(size 1.27 1.27)
					(thickness 0.15)
				)
				(justify left bottom)
				(hide yes)
			)
		)
		(property "Description" ""
			(at 154.94 243.84 0)
			(effects
				(font
					(size 1.27 1.27)
				)
				(hide yes)
			)
		)
		(property "Author" "Antmicro"
			(at 163.83 251.46 0)
			(effects
				(font
					(size 1.27 1.27)
					(thickness 0.15)
				)
				(justify left bottom)
				(hide yes)
			)
		)
		(property "License" "Apache-2.0"
			(at 163.83 254 0)
			(effects
				(font
					(size 1.27 1.27)
					(thickness 0.15)
				)
				(justify left bottom)
				(hide yes)
			)
		)
		(pin "1"
		)
		(instances
			(project "OCuLink to 10GbE adapter"
				(path ""
					(reference "#PWR083")
					(unit 1)
				)
			)
		)
	)
	(symbol
		(lib_id "antmicroCapacitors0402:C_1u_25V_0402")
		(at 167.64 105.41 90)
		(unit 1)
		(exclude_from_sim no)
		(in_bom yes)
		(on_board yes)
		(dnp no)
		(property "Reference" "C56"
			(at 169.672 101.6 90)
			(effects
				(font
					(size 1.27 1.27)
					(thickness 0.15)
				)
				(justify right)
			)
		)
		(property "Value" "C_1u_25V_0402"
			(at 177.8 85.09 0)
			(effects
				(font
					(size 1.27 1.27)
					(thickness 0.15)
				)
				(justify left bottom)
				(hide yes)
			)
		)
		(property "Footprint" "antmicro-footprints:C_0402_1005Metric"
			(at 180.34 85.09 0)
			(effects
				(font
					(size 1.27 1.27)
					(thickness 0.15)
				)
				(justify left bottom)
				(hide yes)
			)
		)
		(property "Datasheet" "https://www.murata.com/products/productdetail?partno=GRM155R61E105KE11%23"
			(at 182.88 85.09 0)
			(effects
				(font
					(size 1.27 1.27)
					(thickness 0.15)
				)
				(justify left bottom)
				(hide yes)
			)
		)
		(property "Description" "SMD Multilayer Ceramic Capacitor, 1 µF, 25 V, 0402 [1005 Metric], ± 10%, X5R, GRM Series"
			(at 167.64 105.41 0)
			(effects
				(font
					(size 1.27 1.27)
				)
				(hide yes)
			)
		)
		(property "MPN" "GRM155R61E105KE11J"
			(at 185.42 85.09 0)
			(effects
				(font
					(size 1.27 1.27)
					(thickness 0.15)
				)
				(justify left bottom)
				(hide yes)
			)
		)
		(property "Manufacturer" "Murata"
			(at 187.96 85.09 0)
			(effects
				(font
					(size 1.27 1.27)
					(thickness 0.15)
				)
				(justify left bottom)
				(hide yes)
			)
		)
		(property "License" "Apache-2.0"
			(at 190.5 85.09 0)
			(effects
				(font
					(size 1.27 1.27)
					(thickness 0.15)
				)
				(justify left bottom)
				(hide yes)
			)
		)
		(property "Author" "Antmicro"
			(at 193.04 85.09 0)
			(effects
				(font
					(size 1.27 1.27)
					(thickness 0.15)
				)
				(justify left bottom)
				(hide yes)
			)
		)
		(property "Val" "1u"
			(at 169.672 104.14 90)
			(effects
				(font
					(size 1.27 1.27)
					(thickness 0.15)
				)
				(justify right)
			)
		)
		(property "Voltage" "25V"
			(at 195.58 85.09 0)
			(effects
				(font
					(size 1.27 1.27)
				)
				(justify left bottom)
				(hide yes)
			)
		)
		(property "Dielectric" "X5R"
			(at 198.12 85.09 0)
			(effects
				(font
					(size 1.27 1.27)
				)
				(justify left bottom)
				(hide yes)
			)
		)
		(pin "1"
		)
		(pin "2"
		)
		(instances
			(project "OCuLink to 10GbE adapter"
				(path ""
					(reference "C56")
					(unit 1)
				)
			)
		)
	)
	(symbol
		(lib_id "antmicropower:GND")
		(at 194.31 107.95 0)
		(unit 1)
		(exclude_from_sim no)
		(in_bom yes)
		(on_board yes)
		(dnp no)
		(property "Reference" "#PWR078"
			(at 203.2 110.49 0)
			(effects
				(font
					(size 1.27 1.27)
					(thickness 0.15)
				)
				(justify left bottom)
				(hide yes)
			)
		)
		(property "Value" "GND"
			(at 194.31 111.76 0)
			(effects
				(font
					(size 1.27 1.27)
					(thickness 0.15)
				)
			)
		)
		(property "Footprint" ""
			(at 203.2 115.57 0)
			(effects
				(font
					(size 1.27 1.27)
					(thickness 0.15)
				)
				(justify left bottom)
				(hide yes)
			)
		)
		(property "Datasheet" ""
			(at 203.2 120.65 0)
			(effects
				(font
					(size 1.27 1.27)
					(thickness 0.15)
				)
				(justify left bottom)
				(hide yes)
			)
		)
		(property "Description" ""
			(at 194.31 107.95 0)
			(effects
				(font
					(size 1.27 1.27)
				)
				(hide yes)
			)
		)
		(property "Author" "Antmicro"
			(at 203.2 115.57 0)
			(effects
				(font
					(size 1.27 1.27)
					(thickness 0.15)
				)
				(justify left bottom)
				(hide yes)
			)
		)
		(property "License" "Apache-2.0"
			(at 203.2 118.11 0)
			(effects
				(font
					(size 1.27 1.27)
					(thickness 0.15)
				)
				(justify left bottom)
				(hide yes)
			)
		)
		(pin "1"
		)
		(instances
			(project "OCuLink to 10GbE adapter"
				(path ""
					(reference "#PWR078")
					(unit 1)
				)
			)
		)
	)
	(symbol
		(lib_id "antmicroCapacitors0402:C_470p_0402")
		(at 254 238.76 90)
		(unit 1)
		(exclude_from_sim no)
		(in_bom yes)
		(on_board yes)
		(dnp no)
		(property "Reference" "C62"
			(at 256.032 234.95 90)
			(effects
				(font
					(size 1.27 1.27)
					(thickness 0.15)
				)
				(justify right)
			)
		)
		(property "Value" "C_470p_0402"
			(at 264.16 218.44 0)
			(effects
				(font
					(size 1.27 1.27)
					(thickness 0.15)
				)
				(justify left bottom)
				(hide yes)
			)
		)
		(property "Footprint" "antmicro-footprints:C_0402_1005Metric"
			(at 266.7 218.44 0)
			(effects
				(font
					(size 1.27 1.27)
					(thickness 0.15)
				)
				(justify left bottom)
				(hide yes)
			)
		)
		(property "Datasheet" "https://www.passivecomponent.com/wp-content/uploads/datasheet/WTC_MLCC_General_Purpose.pdf"
			(at 269.24 218.44 0)
			(effects
				(font
					(size 1.27 1.27)
					(thickness 0.15)
				)
				(justify left bottom)
				(hide yes)
			)
		)
		(property "Description" "SMD Multilayer Ceramic Capacitor, General Purpose, 470 pF, 25 V, 0402 [1005 Metric], ± 10%, X7R"
			(at 254 238.76 0)
			(effects
				(font
					(size 1.27 1.27)
				)
				(hide yes)
			)
		)
		(property "MPN" "0402B471K250CT"
			(at 271.78 218.44 0)
			(effects
				(font
					(size 1.27 1.27)
					(thickness 0.15)
				)
				(justify left bottom)
				(hide yes)
			)
		)
		(property "Manufacturer" "Walsin"
			(at 274.32 218.44 0)
			(effects
				(font
					(size 1.27 1.27)
					(thickness 0.15)
				)
				(justify left bottom)
				(hide yes)
			)
		)
		(property "License" "Apache-2.0"
			(at 276.86 218.44 0)
			(effects
				(font
					(size 1.27 1.27)
					(thickness 0.15)
				)
				(justify left bottom)
				(hide yes)
			)
		)
		(property "Author" "Antmicro"
			(at 279.4 218.44 0)
			(effects
				(font
					(size 1.27 1.27)
					(thickness 0.15)
				)
				(justify left bottom)
				(hide yes)
			)
		)
		(property "Val" "470p"
			(at 256.032 237.49 90)
			(effects
				(font
					(size 1.27 1.27)
					(thickness 0.15)
				)
				(justify right)
			)
		)
		(property "Voltage" "25V"
			(at 281.94 218.44 0)
			(effects
				(font
					(size 1.27 1.27)
				)
				(justify left bottom)
				(hide yes)
			)
		)
		(property "Dielectric" "X7R"
			(at 284.48 218.44 0)
			(effects
				(font
					(size 1.27 1.27)
				)
				(justify left bottom)
				(hide yes)
			)
		)
		(pin "2"
		)
		(pin "1"
		)
		(instances
			(project "OCuLink to 10GbE adapter"
				(path ""
					(reference "C62")
					(unit 1)
				)
			)
		)
	)
	(symbol
		(lib_id "antmicroCapacitors0402:C_1u_25V_0402")
		(at 194.31 241.3 90)
		(unit 1)
		(exclude_from_sim no)
		(in_bom yes)
		(on_board yes)
		(dnp no)
		(property "Reference" "C67"
			(at 196.342 237.49 90)
			(effects
				(font
					(size 1.27 1.27)
					(thickness 0.15)
				)
				(justify right)
			)
		)
		(property "Value" "C_1u_25V_0402"
			(at 204.47 220.98 0)
			(effects
				(font
					(size 1.27 1.27)
					(thickness 0.15)
				)
				(justify left bottom)
				(hide yes)
			)
		)
		(property "Footprint" "antmicro-footprints:C_0402_1005Metric"
			(at 207.01 220.98 0)
			(effects
				(font
					(size 1.27 1.27)
					(thickness 0.15)
				)
				(justify left bottom)
				(hide yes)
			)
		)
		(property "Datasheet" "https://www.murata.com/products/productdetail?partno=GRM155R61E105KE11%23"
			(at 209.55 220.98 0)
			(effects
				(font
					(size 1.27 1.27)
					(thickness 0.15)
				)
				(justify left bottom)
				(hide yes)
			)
		)
		(property "Description" "SMD Multilayer Ceramic Capacitor, 1 µF, 25 V, 0402 [1005 Metric], ± 10%, X5R, GRM Series"
			(at 194.31 241.3 0)
			(effects
				(font
					(size 1.27 1.27)
				)
				(hide yes)
			)
		)
		(property "MPN" "GRM155R61E105KE11J"
			(at 212.09 220.98 0)
			(effects
				(font
					(size 1.27 1.27)
					(thickness 0.15)
				)
				(justify left bottom)
				(hide yes)
			)
		)
		(property "Manufacturer" "Murata"
			(at 214.63 220.98 0)
			(effects
				(font
					(size 1.27 1.27)
					(thickness 0.15)
				)
				(justify left bottom)
				(hide yes)
			)
		)
		(property "License" "Apache-2.0"
			(at 217.17 220.98 0)
			(effects
				(font
					(size 1.27 1.27)
					(thickness 0.15)
				)
				(justify left bottom)
				(hide yes)
			)
		)
		(property "Author" "Antmicro"
			(at 219.71 220.98 0)
			(effects
				(font
					(size 1.27 1.27)
					(thickness 0.15)
				)
				(justify left bottom)
				(hide yes)
			)
		)
		(property "Val" "1u"
			(at 196.342 240.03 90)
			(effects
				(font
					(size 1.27 1.27)
					(thickness 0.15)
				)
				(justify right)
			)
		)
		(property "Voltage" "25V"
			(at 222.25 220.98 0)
			(effects
				(font
					(size 1.27 1.27)
				)
				(justify left bottom)
				(hide yes)
			)
		)
		(property "Dielectric" "X5R"
			(at 224.79 220.98 0)
			(effects
				(font
					(size 1.27 1.27)
				)
				(justify left bottom)
				(hide yes)
			)
		)
		(pin "1"
		)
		(pin "2"
		)
		(instances
			(project "OCuLink to 10GbE adapter"
				(path ""
					(reference "C67")
					(unit 1)
				)
			)
		)
	)
	(symbol
		(lib_id "antmicroResistors0402:R_220R_0402")
		(at 259.08 218.44 0)
		(unit 1)
		(exclude_from_sim no)
		(in_bom yes)
		(on_board yes)
		(dnp no)
		(property "Reference" "R39"
			(at 259.08 217.17 0)
			(effects
				(font
					(size 1.27 1.27)
					(thickness 0.15)
				)
				(justify right)
			)
		)
		(property "Value" "R_220R_0402"
			(at 279.4 231.14 0)
			(effects
				(font
					(size 1.27 1.27)
					(thickness 0.15)
				)
				(justify left bottom)
				(hide yes)
			)
		)
		(property "Footprint" "antmicro-footprints:R_0402_1005Metric"
			(at 279.4 233.68 0)
			(effects
				(font
					(size 1.27 1.27)
					(thickness 0.15)
				)
				(justify left bottom)
				(hide yes)
			)
		)
		(property "Datasheet" "https://www.bourns.com/docs/product-datasheets/cr.pdf"
			(at 279.4 236.22 0)
			(effects
				(font
					(size 1.27 1.27)
					(thickness 0.15)
				)
				(justify left bottom)
				(hide yes)
			)
		)
		(property "Description" "SMD Chip Resistor, 220 ohm, ± 1%, 62.5 mW, 0402 [1005 Metric], Thick Film, General Purpose"
			(at 259.08 218.44 0)
			(effects
				(font
					(size 1.27 1.27)
				)
				(hide yes)
			)
		)
		(property "MPN" "CR0402-FX-2200GLF"
			(at 279.4 238.76 0)
			(effects
				(font
					(size 1.27 1.27)
					(thickness 0.15)
				)
				(justify left bottom)
				(hide yes)
			)
		)
		(property "Manufacturer" "Bourns"
			(at 279.4 241.3 0)
			(effects
				(font
					(size 1.27 1.27)
					(thickness 0.15)
				)
				(justify left bottom)
				(hide yes)
			)
		)
		(property "License" "Apache-2.0"
			(at 279.4 243.84 0)
			(effects
				(font
					(size 1.27 1.27)
					(thickness 0.15)
				)
				(justify left bottom)
				(hide yes)
			)
		)
		(property "Author" "Antmicro"
			(at 279.4 246.38 0)
			(effects
				(font
					(size 1.27 1.27)
					(thickness 0.15)
				)
				(justify left bottom)
				(hide yes)
			)
		)
		(property "Val" "220R"
			(at 264.16 217.17 0)
			(effects
				(font
					(size 1.27 1.27)
					(thickness 0.15)
				)
				(justify left)
			)
		)
		(property "Tolerance" "1%"
			(at 279.4 228.6 0)
			(effects
				(font
					(size 1.27 1.27)
				)
				(justify left bottom)
				(hide yes)
			)
		)
		(pin "1"
		)
		(pin "2"
		)
		(instances
			(project "OCuLink to 10GbE adapter"
				(path ""
					(reference "R39")
					(unit 1)
				)
			)
		)
	)
	(symbol
		(lib_id "antmicropower:GND")
		(at 176.53 107.95 0)
		(unit 1)
		(exclude_from_sim no)
		(in_bom yes)
		(on_board yes)
		(dnp no)
		(property "Reference" "#PWR076"
			(at 185.42 110.49 0)
			(effects
				(font
					(size 1.27 1.27)
					(thickness 0.15)
				)
				(justify left bottom)
				(hide yes)
			)
		)
		(property "Value" "GND"
			(at 176.53 111.76 0)
			(effects
				(font
					(size 1.27 1.27)
					(thickness 0.15)
				)
			)
		)
		(property "Footprint" ""
			(at 185.42 115.57 0)
			(effects
				(font
					(size 1.27 1.27)
					(thickness 0.15)
				)
				(justify left bottom)
				(hide yes)
			)
		)
		(property "Datasheet" ""
			(at 185.42 120.65 0)
			(effects
				(font
					(size 1.27 1.27)
					(thickness 0.15)
				)
				(justify left bottom)
				(hide yes)
			)
		)
		(property "Description" ""
			(at 176.53 107.95 0)
			(effects
				(font
					(size 1.27 1.27)
				)
				(hide yes)
			)
		)
		(property "Author" "Antmicro"
			(at 185.42 115.57 0)
			(effects
				(font
					(size 1.27 1.27)
					(thickness 0.15)
				)
				(justify left bottom)
				(hide yes)
			)
		)
		(property "License" "Apache-2.0"
			(at 185.42 118.11 0)
			(effects
				(font
					(size 1.27 1.27)
					(thickness 0.15)
				)
				(justify left bottom)
				(hide yes)
			)
		)
		(pin "1"
		)
		(instances
			(project "OCuLink to 10GbE adapter"
				(path ""
					(reference "#PWR076")
					(unit 1)
				)
			)
		)
	)
	(symbol
		(lib_id "antmicroCapacitors0402:C_1u_25V_0402")
		(at 176.53 241.3 90)
		(unit 1)
		(exclude_from_sim no)
		(in_bom yes)
		(on_board yes)
		(dnp no)
		(property "Reference" "C65"
			(at 178.562 237.49 90)
			(effects
				(font
					(size 1.27 1.27)
					(thickness 0.15)
				)
				(justify right)
			)
		)
		(property "Value" "C_1u_25V_0402"
			(at 186.69 220.98 0)
			(effects
				(font
					(size 1.27 1.27)
					(thickness 0.15)
				)
				(justify left bottom)
				(hide yes)
			)
		)
		(property "Footprint" "antmicro-footprints:C_0402_1005Metric"
			(at 189.23 220.98 0)
			(effects
				(font
					(size 1.27 1.27)
					(thickness 0.15)
				)
				(justify left bottom)
				(hide yes)
			)
		)
		(property "Datasheet" "https://www.murata.com/products/productdetail?partno=GRM155R61E105KE11%23"
			(at 191.77 220.98 0)
			(effects
				(font
					(size 1.27 1.27)
					(thickness 0.15)
				)
				(justify left bottom)
				(hide yes)
			)
		)
		(property "Description" "SMD Multilayer Ceramic Capacitor, 1 µF, 25 V, 0402 [1005 Metric], ± 10%, X5R, GRM Series"
			(at 176.53 241.3 0)
			(effects
				(font
					(size 1.27 1.27)
				)
				(hide yes)
			)
		)
		(property "MPN" "GRM155R61E105KE11J"
			(at 194.31 220.98 0)
			(effects
				(font
					(size 1.27 1.27)
					(thickness 0.15)
				)
				(justify left bottom)
				(hide yes)
			)
		)
		(property "Manufacturer" "Murata"
			(at 196.85 220.98 0)
			(effects
				(font
					(size 1.27 1.27)
					(thickness 0.15)
				)
				(justify left bottom)
				(hide yes)
			)
		)
		(property "License" "Apache-2.0"
			(at 199.39 220.98 0)
			(effects
				(font
					(size 1.27 1.27)
					(thickness 0.15)
				)
				(justify left bottom)
				(hide yes)
			)
		)
		(property "Author" "Antmicro"
			(at 201.93 220.98 0)
			(effects
				(font
					(size 1.27 1.27)
					(thickness 0.15)
				)
				(justify left bottom)
				(hide yes)
			)
		)
		(property "Val" "1u"
			(at 178.562 240.03 90)
			(effects
				(font
					(size 1.27 1.27)
					(thickness 0.15)
				)
				(justify right)
			)
		)
		(property "Voltage" "25V"
			(at 204.47 220.98 0)
			(effects
				(font
					(size 1.27 1.27)
				)
				(justify left bottom)
				(hide yes)
			)
		)
		(property "Dielectric" "X5R"
			(at 207.01 220.98 0)
			(effects
				(font
					(size 1.27 1.27)
				)
				(justify left bottom)
				(hide yes)
			)
		)
		(pin "1"
		)
		(pin "2"
		)
		(instances
			(project "OCuLink to 10GbE adapter"
				(path ""
					(reference "C65")
					(unit 1)
				)
			)
		)
	)
	(symbol
		(lib_id "antmicroFixedInductors:L_2n4_0.85A_0402")
		(at 147.32 97.79 0)
		(unit 1)
		(exclude_from_sim no)
		(in_bom yes)
		(on_board yes)
		(dnp no)
		(property "Reference" "L6"
			(at 149.86 93.218 0)
			(effects
				(font
					(size 1.27 1.27)
					(thickness 0.15)
				)
			)
		)
		(property "Value" "L_2n4_0.85A_0402"
			(at 161.29 100.33 0)
			(effects
				(font
					(size 1.27 1.27)
					(thickness 0.15)
				)
				(justify left bottom)
				(hide yes)
			)
		)
		(property "Footprint" "antmicro-footprints:L_0402_1005Metric"
			(at 161.29 105.41 0)
			(effects
				(font
					(size 1.27 1.27)
					(thickness 0.15)
				)
				(justify left bottom)
				(hide yes)
			)
		)
		(property "Datasheet" "https://www.murata.com/products/productdetail?partno=LQW15AN2N4B00%23"
			(at 161.29 107.95 0)
			(effects
				(font
					(size 1.27 1.27)
					(thickness 0.15)
				)
				(justify left bottom)
				(hide yes)
			)
		)
		(property "Description" "Wirewound Inductor, 2.4 nH, 0.05 ohm, 15 GHz, 850 mA, 0402 [1005 Metric], LQW15AN"
			(at 147.32 97.79 0)
			(effects
				(font
					(size 1.27 1.27)
				)
				(hide yes)
			)
		)
		(property "Val" "2n4/0.85A"
			(at 149.86 95.758 0)
			(effects
				(font
					(size 1.27 1.27)
					(thickness 0.15)
				)
			)
		)
		(property "Manufacturer" "Murata"
			(at 161.29 110.49 0)
			(effects
				(font
					(size 1.27 1.27)
					(thickness 0.15)
				)
				(justify left bottom)
				(hide yes)
			)
		)
		(property "MPN" "LQW15AN2N4B00D"
			(at 161.29 113.03 0)
			(effects
				(font
					(size 1.27 1.27)
					(thickness 0.15)
				)
				(justify left bottom)
				(hide yes)
			)
		)
		(property "ISat" "0.85 A"
			(at 161.29 114.3 0)
			(effects
				(font
					(size 1.27 1.27)
				)
				(justify left)
				(hide yes)
			)
		)
		(property "IMax" "0.85 A"
			(at 161.29 118.11 0)
			(effects
				(font
					(size 1.27 1.27)
					(thickness 0.15)
				)
				(justify left bottom)
				(hide yes)
			)
		)
		(property "Size" "1.0x0.5"
			(at 161.29 120.65 0)
			(effects
				(font
					(size 1.27 1.27)
					(thickness 0.15)
				)
				(justify left bottom)
				(hide yes)
			)
		)
		(property "Author" "Antmicro"
			(at 161.29 123.19 0)
			(effects
				(font
					(size 1.27 1.27)
					(thickness 0.15)
				)
				(justify left bottom)
				(hide yes)
			)
		)
		(property "License" "Apache-2.0"
			(at 161.29 125.73 0)
			(effects
				(font
					(size 1.27 1.27)
					(thickness 0.15)
				)
				(justify left bottom)
				(hide yes)
			)
		)
		(pin "2"
		)
		(pin "1"
		)
		(instances
			(project ""
				(path ""
					(reference "L6")
					(unit 1)
				)
			)
		)
	)
	(symbol
		(lib_id "antmicropower:GND")
		(at 95.25 107.95 0)
		(unit 1)
		(exclude_from_sim no)
		(in_bom yes)
		(on_board yes)
		(dnp no)
		(property "Reference" "#PWR073"
			(at 104.14 110.49 0)
			(effects
				(font
					(size 1.27 1.27)
					(thickness 0.15)
				)
				(justify left bottom)
				(hide yes)
			)
		)
		(property "Value" "GND"
			(at 95.25 111.76 0)
			(effects
				(font
					(size 1.27 1.27)
					(thickness 0.15)
				)
			)
		)
		(property "Footprint" ""
			(at 104.14 115.57 0)
			(effects
				(font
					(size 1.27 1.27)
					(thickness 0.15)
				)
				(justify left bottom)
				(hide yes)
			)
		)
		(property "Datasheet" ""
			(at 104.14 120.65 0)
			(effects
				(font
					(size 1.27 1.27)
					(thickness 0.15)
				)
				(justify left bottom)
				(hide yes)
			)
		)
		(property "Description" ""
			(at 95.25 107.95 0)
			(effects
				(font
					(size 1.27 1.27)
				)
				(hide yes)
			)
		)
		(property "Author" "Antmicro"
			(at 104.14 115.57 0)
			(effects
				(font
					(size 1.27 1.27)
					(thickness 0.15)
				)
				(justify left bottom)
				(hide yes)
			)
		)
		(property "License" "Apache-2.0"
			(at 104.14 118.11 0)
			(effects
				(font
					(size 1.27 1.27)
					(thickness 0.15)
				)
				(justify left bottom)
				(hide yes)
			)
		)
		(pin "1"
		)
		(instances
			(project "OCuLink to 10GbE adapter"
				(path ""
					(reference "#PWR073")
					(unit 1)
				)
			)
		)
	)
	(symbol
		(lib_id "antmicroCapacitors0402:C_1u_25V_0402")
		(at 176.53 105.41 90)
		(unit 1)
		(exclude_from_sim no)
		(in_bom yes)
		(on_board yes)
		(dnp no)
		(property "Reference" "C57"
			(at 178.562 101.6 90)
			(effects
				(font
					(size 1.27 1.27)
					(thickness 0.15)
				)
				(justify right)
			)
		)
		(property "Value" "C_1u_25V_0402"
			(at 186.69 85.09 0)
			(effects
				(font
					(size 1.27 1.27)
					(thickness 0.15)
				)
				(justify left bottom)
				(hide yes)
			)
		)
		(property "Footprint" "antmicro-footprints:C_0402_1005Metric"
			(at 189.23 85.09 0)
			(effects
				(font
					(size 1.27 1.27)
					(thickness 0.15)
				)
				(justify left bottom)
				(hide yes)
			)
		)
		(property "Datasheet" "https://www.murata.com/products/productdetail?partno=GRM155R61E105KE11%23"
			(at 191.77 85.09 0)
			(effects
				(font
					(size 1.27 1.27)
					(thickness 0.15)
				)
				(justify left bottom)
				(hide yes)
			)
		)
		(property "Description" "SMD Multilayer Ceramic Capacitor, 1 µF, 25 V, 0402 [1005 Metric], ± 10%, X5R, GRM Series"
			(at 176.53 105.41 0)
			(effects
				(font
					(size 1.27 1.27)
				)
				(hide yes)
			)
		)
		(property "MPN" "GRM155R61E105KE11J"
			(at 194.31 85.09 0)
			(effects
				(font
					(size 1.27 1.27)
					(thickness 0.15)
				)
				(justify left bottom)
				(hide yes)
			)
		)
		(property "Manufacturer" "Murata"
			(at 196.85 85.09 0)
			(effects
				(font
					(size 1.27 1.27)
					(thickness 0.15)
				)
				(justify left bottom)
				(hide yes)
			)
		)
		(property "License" "Apache-2.0"
			(at 199.39 85.09 0)
			(effects
				(font
					(size 1.27 1.27)
					(thickness 0.15)
				)
				(justify left bottom)
				(hide yes)
			)
		)
		(property "Author" "Antmicro"
			(at 201.93 85.09 0)
			(effects
				(font
					(size 1.27 1.27)
					(thickness 0.15)
				)
				(justify left bottom)
				(hide yes)
			)
		)
		(property "Val" "1u"
			(at 178.562 104.14 90)
			(effects
				(font
					(size 1.27 1.27)
					(thickness 0.15)
				)
				(justify right)
			)
		)
		(property "Voltage" "25V"
			(at 204.47 85.09 0)
			(effects
				(font
					(size 1.27 1.27)
				)
				(justify left bottom)
				(hide yes)
			)
		)
		(property "Dielectric" "X5R"
			(at 207.01 85.09 0)
			(effects
				(font
					(size 1.27 1.27)
				)
				(justify left bottom)
				(hide yes)
			)
		)
		(pin "1"
		)
		(pin "2"
		)
		(instances
			(project "OCuLink to 10GbE adapter"
				(path ""
					(reference "C57")
					(unit 1)
				)
			)
		)
	)
	(symbol
		(lib_id "antmicropower:GND")
		(at 71.12 107.95 0)
		(unit 1)
		(exclude_from_sim no)
		(in_bom yes)
		(on_board yes)
		(dnp no)
		(property "Reference" "#PWR071"
			(at 80.01 110.49 0)
			(effects
				(font
					(size 1.27 1.27)
					(thickness 0.15)
				)
				(justify left bottom)
				(hide yes)
			)
		)
		(property "Value" "GND"
			(at 71.12 111.76 0)
			(effects
				(font
					(size 1.27 1.27)
					(thickness 0.15)
				)
			)
		)
		(property "Footprint" ""
			(at 80.01 115.57 0)
			(effects
				(font
					(size 1.27 1.27)
					(thickness 0.15)
				)
				(justify left bottom)
				(hide yes)
			)
		)
		(property "Datasheet" ""
			(at 80.01 120.65 0)
			(effects
				(font
					(size 1.27 1.27)
					(thickness 0.15)
				)
				(justify left bottom)
				(hide yes)
			)
		)
		(property "Description" ""
			(at 71.12 107.95 0)
			(effects
				(font
					(size 1.27 1.27)
				)
				(hide yes)
			)
		)
		(property "Author" "Antmicro"
			(at 80.01 115.57 0)
			(effects
				(font
					(size 1.27 1.27)
					(thickness 0.15)
				)
				(justify left bottom)
				(hide yes)
			)
		)
		(property "License" "Apache-2.0"
			(at 80.01 118.11 0)
			(effects
				(font
					(size 1.27 1.27)
					(thickness 0.15)
				)
				(justify left bottom)
				(hide yes)
			)
		)
		(pin "1"
		)
		(instances
			(project "OCuLink to 10GbE adapter"
				(path ""
					(reference "#PWR071")
					(unit 1)
				)
			)
		)
	)
	(symbol
		(lib_id "antmicroCapacitors0402:C_1u_25V_0402")
		(at 194.31 105.41 90)
		(unit 1)
		(exclude_from_sim no)
		(in_bom yes)
		(on_board yes)
		(dnp no)
		(property "Reference" "C59"
			(at 196.342 101.6 90)
			(effects
				(font
					(size 1.27 1.27)
					(thickness 0.15)
				)
				(justify right)
			)
		)
		(property "Value" "C_1u_25V_0402"
			(at 204.47 85.09 0)
			(effects
				(font
					(size 1.27 1.27)
					(thickness 0.15)
				)
				(justify left bottom)
				(hide yes)
			)
		)
		(property "Footprint" "antmicro-footprints:C_0402_1005Metric"
			(at 207.01 85.09 0)
			(effects
				(font
					(size 1.27 1.27)
					(thickness 0.15)
				)
				(justify left bottom)
				(hide yes)
			)
		)
		(property "Datasheet" "https://www.murata.com/products/productdetail?partno=GRM155R61E105KE11%23"
			(at 209.55 85.09 0)
			(effects
				(font
					(size 1.27 1.27)
					(thickness 0.15)
				)
				(justify left bottom)
				(hide yes)
			)
		)
		(property "Description" "SMD Multilayer Ceramic Capacitor, 1 µF, 25 V, 0402 [1005 Metric], ± 10%, X5R, GRM Series"
			(at 194.31 105.41 0)
			(effects
				(font
					(size 1.27 1.27)
				)
				(hide yes)
			)
		)
		(property "MPN" "GRM155R61E105KE11J"
			(at 212.09 85.09 0)
			(effects
				(font
					(size 1.27 1.27)
					(thickness 0.15)
				)
				(justify left bottom)
				(hide yes)
			)
		)
		(property "Manufacturer" "Murata"
			(at 214.63 85.09 0)
			(effects
				(font
					(size 1.27 1.27)
					(thickness 0.15)
				)
				(justify left bottom)
				(hide yes)
			)
		)
		(property "License" "Apache-2.0"
			(at 217.17 85.09 0)
			(effects
				(font
					(size 1.27 1.27)
					(thickness 0.15)
				)
				(justify left bottom)
				(hide yes)
			)
		)
		(property "Author" "Antmicro"
			(at 219.71 85.09 0)
			(effects
				(font
					(size 1.27 1.27)
					(thickness 0.15)
				)
				(justify left bottom)
				(hide yes)
			)
		)
		(property "Val" "1u"
			(at 196.342 104.14 90)
			(effects
				(font
					(size 1.27 1.27)
					(thickness 0.15)
				)
				(justify right)
			)
		)
		(property "Voltage" "25V"
			(at 222.25 85.09 0)
			(effects
				(font
					(size 1.27 1.27)
				)
				(justify left bottom)
				(hide yes)
			)
		)
		(property "Dielectric" "X5R"
			(at 224.79 85.09 0)
			(effects
				(font
					(size 1.27 1.27)
				)
				(justify left bottom)
				(hide yes)
			)
		)
		(pin "1"
		)
		(pin "2"
		)
		(instances
			(project ""
				(path ""
					(reference "C59")
					(unit 1)
				)
			)
		)
	)
	(symbol
		(lib_id "antmicropower:+1V8")
		(at 92.71 95.25 0)
		(unit 1)
		(exclude_from_sim no)
		(in_bom yes)
		(on_board yes)
		(dnp no)
		(property "Reference" "#PWR068"
			(at 107.95 97.79 0)
			(effects
				(font
					(size 1.27 1.27)
					(thickness 0.15)
				)
				(justify left bottom)
				(hide yes)
			)
		)
		(property "Value" "+1V88_CT"
			(at 92.71 91.44 0)
			(effects
				(font
					(size 1.27 1.27)
					(thickness 0.15)
				)
			)
		)
		(property "Footprint" ""
			(at 107.95 102.87 0)
			(effects
				(font
					(size 1.27 1.27)
					(thickness 0.15)
				)
				(justify left bottom)
				(hide yes)
			)
		)
		(property "Datasheet" ""
			(at 107.95 105.41 0)
			(effects
				(font
					(size 1.27 1.27)
					(thickness 0.15)
				)
				(justify left bottom)
				(hide yes)
			)
		)
		(property "Description" ""
			(at 92.71 95.25 0)
			(effects
				(font
					(size 1.27 1.27)
				)
				(hide yes)
			)
		)
		(property "Author" "Antmicro"
			(at 107.95 100.33 0)
			(effects
				(font
					(size 1.27 1.27)
					(thickness 0.15)
				)
				(justify left bottom)
				(hide yes)
			)
		)
		(property "License" "Apache-2.0"
			(at 107.95 102.87 0)
			(effects
				(font
					(size 1.27 1.27)
					(thickness 0.15)
				)
				(justify left bottom)
				(hide yes)
			)
		)
		(pin "1"
		)
		(instances
			(project "OCuLink to 10GbE adapter"
				(path ""
					(reference "#PWR068")
					(unit 1)
				)
			)
		)
	)
	(symbol
		(lib_id "antmicroCapacitors0402:C_470p_0402")
		(at 233.68 238.76 90)
		(unit 1)
		(exclude_from_sim no)
		(in_bom yes)
		(on_board yes)
		(dnp no)
		(property "Reference" "C60"
			(at 235.712 234.95 90)
			(effects
				(font
					(size 1.27 1.27)
					(thickness 0.15)
				)
				(justify right)
			)
		)
		(property "Value" "C_470p_0402"
			(at 243.84 218.44 0)
			(effects
				(font
					(size 1.27 1.27)
					(thickness 0.15)
				)
				(justify left bottom)
				(hide yes)
			)
		)
		(property "Footprint" "antmicro-footprints:C_0402_1005Metric"
			(at 246.38 218.44 0)
			(effects
				(font
					(size 1.27 1.27)
					(thickness 0.15)
				)
				(justify left bottom)
				(hide yes)
			)
		)
		(property "Datasheet" "https://www.passivecomponent.com/wp-content/uploads/datasheet/WTC_MLCC_General_Purpose.pdf"
			(at 248.92 218.44 0)
			(effects
				(font
					(size 1.27 1.27)
					(thickness 0.15)
				)
				(justify left bottom)
				(hide yes)
			)
		)
		(property "Description" "SMD Multilayer Ceramic Capacitor, General Purpose, 470 pF, 25 V, 0402 [1005 Metric], ± 10%, X7R"
			(at 233.68 238.76 0)
			(effects
				(font
					(size 1.27 1.27)
				)
				(hide yes)
			)
		)
		(property "MPN" "0402B471K250CT"
			(at 251.46 218.44 0)
			(effects
				(font
					(size 1.27 1.27)
					(thickness 0.15)
				)
				(justify left bottom)
				(hide yes)
			)
		)
		(property "Manufacturer" "Walsin"
			(at 254 218.44 0)
			(effects
				(font
					(size 1.27 1.27)
					(thickness 0.15)
				)
				(justify left bottom)
				(hide yes)
			)
		)
		(property "License" "Apache-2.0"
			(at 256.54 218.44 0)
			(effects
				(font
					(size 1.27 1.27)
					(thickness 0.15)
				)
				(justify left bottom)
				(hide yes)
			)
		)
		(property "Author" "Antmicro"
			(at 259.08 218.44 0)
			(effects
				(font
					(size 1.27 1.27)
					(thickness 0.15)
				)
				(justify left bottom)
				(hide yes)
			)
		)
		(property "Val" "470p"
			(at 235.712 237.49 90)
			(effects
				(font
					(size 1.27 1.27)
					(thickness 0.15)
				)
				(justify right)
			)
		)
		(property "Voltage" "25V"
			(at 261.62 218.44 0)
			(effects
				(font
					(size 1.27 1.27)
				)
				(justify left bottom)
				(hide yes)
			)
		)
		(property "Dielectric" "X7R"
			(at 264.16 218.44 0)
			(effects
				(font
					(size 1.27 1.27)
				)
				(justify left bottom)
				(hide yes)
			)
		)
		(pin "2"
		)
		(pin "1"
		)
		(instances
			(project "OCuLink to 10GbE adapter"
				(path ""
					(reference "C60")
					(unit 1)
				)
			)
		)
	)
	(symbol
		(lib_id "antmicroCapacitors0402:C_1u_25V_0402")
		(at 167.64 241.3 90)
		(unit 1)
		(exclude_from_sim no)
		(in_bom yes)
		(on_board yes)
		(dnp no)
		(property "Reference" "C64"
			(at 169.672 237.49 90)
			(effects
				(font
					(size 1.27 1.27)
					(thickness 0.15)
				)
				(justify right)
			)
		)
		(property "Value" "C_1u_25V_0402"
			(at 177.8 220.98 0)
			(effects
				(font
					(size 1.27 1.27)
					(thickness 0.15)
				)
				(justify left bottom)
				(hide yes)
			)
		)
		(property "Footprint" "antmicro-footprints:C_0402_1005Metric"
			(at 180.34 220.98 0)
			(effects
				(font
					(size 1.27 1.27)
					(thickness 0.15)
				)
				(justify left bottom)
				(hide yes)
			)
		)
		(property "Datasheet" "https://www.murata.com/products/productdetail?partno=GRM155R61E105KE11%23"
			(at 182.88 220.98 0)
			(effects
				(font
					(size 1.27 1.27)
					(thickness 0.15)
				)
				(justify left bottom)
				(hide yes)
			)
		)
		(property "Description" "SMD Multilayer Ceramic Capacitor, 1 µF, 25 V, 0402 [1005 Metric], ± 10%, X5R, GRM Series"
			(at 167.64 241.3 0)
			(effects
				(font
					(size 1.27 1.27)
				)
				(hide yes)
			)
		)
		(property "MPN" "GRM155R61E105KE11J"
			(at 185.42 220.98 0)
			(effects
				(font
					(size 1.27 1.27)
					(thickness 0.15)
				)
				(justify left bottom)
				(hide yes)
			)
		)
		(property "Manufacturer" "Murata"
			(at 187.96 220.98 0)
			(effects
				(font
					(size 1.27 1.27)
					(thickness 0.15)
				)
				(justify left bottom)
				(hide yes)
			)
		)
		(property "License" "Apache-2.0"
			(at 190.5 220.98 0)
			(effects
				(font
					(size 1.27 1.27)
					(thickness 0.15)
				)
				(justify left bottom)
				(hide yes)
			)
		)
		(property "Author" "Antmicro"
			(at 193.04 220.98 0)
			(effects
				(font
					(size 1.27 1.27)
					(thickness 0.15)
				)
				(justify left bottom)
				(hide yes)
			)
		)
		(property "Val" "1u"
			(at 169.672 240.03 90)
			(effects
				(font
					(size 1.27 1.27)
					(thickness 0.15)
				)
				(justify right)
			)
		)
		(property "Voltage" "25V"
			(at 195.58 220.98 0)
			(effects
				(font
					(size 1.27 1.27)
				)
				(justify left bottom)
				(hide yes)
			)
		)
		(property "Dielectric" "X5R"
			(at 198.12 220.98 0)
			(effects
				(font
					(size 1.27 1.27)
				)
				(justify left bottom)
				(hide yes)
			)
		)
		(pin "1"
		)
		(pin "2"
		)
		(instances
			(project "OCuLink to 10GbE adapter"
				(path ""
					(reference "C64")
					(unit 1)
				)
			)
		)
	)
	(symbol
		(lib_id "antmicroCapacitors0402:C_100n_0402")
		(at 59.69 105.41 90)
		(unit 1)
		(exclude_from_sim no)
		(in_bom yes)
		(on_board yes)
		(dnp no)
		(property "Reference" "C51"
			(at 61.722 101.6 90)
			(effects
				(font
					(size 1.27 1.27)
					(thickness 0.15)
				)
				(justify right)
			)
		)
		(property "Value" "C_100n_0402"
			(at 82.55 90.17 0)
			(effects
				(font
					(size 1.27 1.27)
					(thickness 0.15)
				)
				(justify left bottom)
				(hide yes)
			)
		)
		(property "Footprint" "antmicro-footprints:C_0402_1005Metric"
			(at 85.09 90.17 0)
			(effects
				(font
					(size 1.27 1.27)
					(thickness 0.15)
				)
				(justify left bottom)
				(hide yes)
			)
		)
		(property "Datasheet" "https://www.murata.com/products/productdetail?partno=GRM155R61H104KE14%23"
			(at 87.63 90.17 0)
			(effects
				(font
					(size 1.27 1.27)
					(thickness 0.15)
				)
				(justify left bottom)
				(hide yes)
			)
		)
		(property "Description" "SMD Multilayer Ceramic Capacitor, 0.1 µF, 50 V, 0402 [1005 Metric], ± 10%, X5R, GRM Series"
			(at 59.69 105.41 0)
			(effects
				(font
					(size 1.27 1.27)
				)
				(hide yes)
			)
		)
		(property "MPN" "GRM155R61H104KE14D"
			(at 90.17 90.17 0)
			(effects
				(font
					(size 1.27 1.27)
					(thickness 0.15)
				)
				(justify left bottom)
				(hide yes)
			)
		)
		(property "Val" "100n"
			(at 61.722 104.14 90)
			(effects
				(font
					(size 1.27 1.27)
					(thickness 0.15)
				)
				(justify right)
			)
		)
		(property "Voltage" "50V"
			(at 69.85 90.17 0)
			(effects
				(font
					(size 1.27 1.27)
					(thickness 0.15)
				)
				(justify left bottom)
				(hide yes)
			)
		)
		(property "Dielectric" "X5R"
			(at 72.39 90.17 0)
			(effects
				(font
					(size 1.27 1.27)
					(thickness 0.15)
				)
				(justify left bottom)
				(hide yes)
			)
		)
		(property "Manufacturer" "Murata"
			(at 74.93 90.17 0)
			(effects
				(font
					(size 1.27 1.27)
					(thickness 0.15)
				)
				(justify left bottom)
				(hide yes)
			)
		)
		(property "License" "Apache-2.0"
			(at 77.47 90.17 0)
			(effects
				(font
					(size 1.27 1.27)
					(thickness 0.15)
				)
				(justify left bottom)
				(hide yes)
			)
		)
		(property "Author" "Antmicro"
			(at 80.01 90.17 0)
			(effects
				(font
					(size 1.27 1.27)
					(thickness 0.15)
				)
				(justify left bottom)
				(hide yes)
			)
		)
		(pin "2"
		)
		(pin "1"
		)
		(instances
			(project ""
				(path ""
					(reference "C51")
					(unit 1)
				)
			)
		)
	)
	(symbol
		(lib_id "antmicropower:GND")
		(at 185.42 107.95 0)
		(unit 1)
		(exclude_from_sim no)
		(in_bom yes)
		(on_board yes)
		(dnp no)
		(property "Reference" "#PWR077"
			(at 194.31 110.49 0)
			(effects
				(font
					(size 1.27 1.27)
					(thickness 0.15)
				)
				(justify left bottom)
				(hide yes)
			)
		)
		(property "Value" "GND"
			(at 185.42 111.76 0)
			(effects
				(font
					(size 1.27 1.27)
					(thickness 0.15)
				)
			)
		)
		(property "Footprint" ""
			(at 194.31 115.57 0)
			(effects
				(font
					(size 1.27 1.27)
					(thickness 0.15)
				)
				(justify left bottom)
				(hide yes)
			)
		)
		(property "Datasheet" ""
			(at 194.31 120.65 0)
			(effects
				(font
					(size 1.27 1.27)
					(thickness 0.15)
				)
				(justify left bottom)
				(hide yes)
			)
		)
		(property "Description" ""
			(at 185.42 107.95 0)
			(effects
				(font
					(size 1.27 1.27)
				)
				(hide yes)
			)
		)
		(property "Author" "Antmicro"
			(at 194.31 115.57 0)
			(effects
				(font
					(size 1.27 1.27)
					(thickness 0.15)
				)
				(justify left bottom)
				(hide yes)
			)
		)
		(property "License" "Apache-2.0"
			(at 194.31 118.11 0)
			(effects
				(font
					(size 1.27 1.27)
					(thickness 0.15)
				)
				(justify left bottom)
				(hide yes)
			)
		)
		(pin "1"
		)
		(instances
			(project "OCuLink to 10GbE adapter"
				(path ""
					(reference "#PWR077")
					(unit 1)
				)
			)
		)
	)
	(symbol
		(lib_id "antmicropower:GND")
		(at 59.69 107.95 0)
		(unit 1)
		(exclude_from_sim no)
		(in_bom yes)
		(on_board yes)
		(dnp no)
		(property "Reference" "#PWR070"
			(at 68.58 110.49 0)
			(effects
				(font
					(size 1.27 1.27)
					(thickness 0.15)
				)
				(justify left bottom)
				(hide yes)
			)
		)
		(property "Value" "GND"
			(at 59.69 111.76 0)
			(effects
				(font
					(size 1.27 1.27)
					(thickness 0.15)
				)
			)
		)
		(property "Footprint" ""
			(at 68.58 115.57 0)
			(effects
				(font
					(size 1.27 1.27)
					(thickness 0.15)
				)
				(justify left bottom)
				(hide yes)
			)
		)
		(property "Datasheet" ""
			(at 68.58 120.65 0)
			(effects
				(font
					(size 1.27 1.27)
					(thickness 0.15)
				)
				(justify left bottom)
				(hide yes)
			)
		)
		(property "Description" ""
			(at 59.69 107.95 0)
			(effects
				(font
					(size 1.27 1.27)
				)
				(hide yes)
			)
		)
		(property "Author" "Antmicro"
			(at 68.58 115.57 0)
			(effects
				(font
					(size 1.27 1.27)
					(thickness 0.15)
				)
				(justify left bottom)
				(hide yes)
			)
		)
		(property "License" "Apache-2.0"
			(at 68.58 118.11 0)
			(effects
				(font
					(size 1.27 1.27)
					(thickness 0.15)
				)
				(justify left bottom)
				(hide yes)
			)
		)
		(pin "1"
		)
		(instances
			(project "OCuLink to 10GbE adapter"
				(path ""
					(reference "#PWR070")
					(unit 1)
				)
			)
		)
	)
	(symbol
		(lib_id "antmicroFerriteBeadsandChips:FB_33Z_3A_Murata-BLM18PG_0603")
		(at 76.2 97.79 0)
		(unit 1)
		(exclude_from_sim no)
		(in_bom yes)
		(on_board yes)
		(dnp no)
		(fields_autoplaced yes)
		(property "Reference" "FB1"
			(at 78.7019 91.44 0)
			(effects
				(font
					(size 1.27 1.27)
					(thickness 0.15)
				)
			)
		)
		(property "Value" "FB_33Z_3A_Murata-BLM18PG_0603"
			(at 90.17 100.33 0)
			(effects
				(font
					(size 1.27 1.27)
					(thickness 0.15)
				)
				(justify left bottom)
				(hide yes)
			)
		)
		(property "Footprint" "antmicro-footprints:FB_0603_1608Metric"
			(at 90.17 105.41 0)
			(effects
				(font
					(size 1.27 1.27)
					(thickness 0.15)
				)
				(justify left bottom)
				(hide yes)
			)
		)
		(property "Datasheet" "https://www.murata.com/products/productdata/8796737273886/QNFA9101.pdf?1649080818000"
			(at 90.17 107.95 0)
			(effects
				(font
					(size 1.27 1.27)
					(thickness 0.15)
				)
				(justify left bottom)
				(hide yes)
			)
		)
		(property "Description" "Ferrite Bead, 0603 [1608 Metric], 33 ohm, 3 A, BLM18PG, 0.025 ohm, ± 25%, DC power line"
			(at 76.2 97.79 0)
			(effects
				(font
					(size 1.27 1.27)
				)
				(hide yes)
			)
		)
		(property "Val" "33Z/3A"
			(at 78.7019 93.98 0)
			(effects
				(font
					(size 1.27 1.27)
				)
			)
		)
		(property "MPN" "BLM18PG330SH1D"
			(at 90.17 110.49 0)
			(effects
				(font
					(size 1.27 1.27)
					(thickness 0.15)
				)
				(justify left bottom)
				(hide yes)
			)
		)
		(property "Manufacturer" "Murata"
			(at 90.17 113.03 0)
			(effects
				(font
					(size 1.27 1.27)
					(thickness 0.15)
				)
				(justify left bottom)
				(hide yes)
			)
		)
		(property "Current" ""
			(at 96.52 120.65 0)
			(effects
				(font
					(size 1.27 1.27)
					(thickness 0.15)
				)
				(justify left bottom)
				(hide yes)
			)
		)
		(property "Author" "Antmicro"
			(at 90.17 115.57 0)
			(effects
				(font
					(size 1.27 1.27)
					(thickness 0.15)
				)
				(justify left bottom)
				(hide yes)
			)
		)
		(property "License" "Apache-2.0"
			(at 90.17 118.11 0)
			(effects
				(font
					(size 1.27 1.27)
					(thickness 0.15)
				)
				(justify left bottom)
				(hide yes)
			)
		)
		(pin "2"
		)
		(pin "1"
		)
		(instances
			(project ""
				(path ""
					(reference "FB1")
					(unit 1)
				)
			)
		)
	)
	(symbol
		(lib_id "antmicroResistors0402:R_220R_0402")
		(at 259.08 228.6 0)
		(unit 1)
		(exclude_from_sim no)
		(in_bom yes)
		(on_board yes)
		(dnp no)
		(property "Reference" "R41"
			(at 259.08 227.33 0)
			(effects
				(font
					(size 1.27 1.27)
					(thickness 0.15)
				)
				(justify right)
			)
		)
		(property "Value" "R_220R_0402"
			(at 279.4 241.3 0)
			(effects
				(font
					(size 1.27 1.27)
					(thickness 0.15)
				)
				(justify left bottom)
				(hide yes)
			)
		)
		(property "Footprint" "antmicro-footprints:R_0402_1005Metric"
			(at 279.4 243.84 0)
			(effects
				(font
					(size 1.27 1.27)
					(thickness 0.15)
				)
				(justify left bottom)
				(hide yes)
			)
		)
		(property "Datasheet" "https://www.bourns.com/docs/product-datasheets/cr.pdf"
			(at 279.4 246.38 0)
			(effects
				(font
					(size 1.27 1.27)
					(thickness 0.15)
				)
				(justify left bottom)
				(hide yes)
			)
		)
		(property "Description" "SMD Chip Resistor, 220 ohm, ± 1%, 62.5 mW, 0402 [1005 Metric], Thick Film, General Purpose"
			(at 259.08 228.6 0)
			(effects
				(font
					(size 1.27 1.27)
				)
				(hide yes)
			)
		)
		(property "MPN" "CR0402-FX-2200GLF"
			(at 279.4 248.92 0)
			(effects
				(font
					(size 1.27 1.27)
					(thickness 0.15)
				)
				(justify left bottom)
				(hide yes)
			)
		)
		(property "Manufacturer" "Bourns"
			(at 279.4 251.46 0)
			(effects
				(font
					(size 1.27 1.27)
					(thickness 0.15)
				)
				(justify left bottom)
				(hide yes)
			)
		)
		(property "License" "Apache-2.0"
			(at 279.4 254 0)
			(effects
				(font
					(size 1.27 1.27)
					(thickness 0.15)
				)
				(justify left bottom)
				(hide yes)
			)
		)
		(property "Author" "Antmicro"
			(at 279.4 256.54 0)
			(effects
				(font
					(size 1.27 1.27)
					(thickness 0.15)
				)
				(justify left bottom)
				(hide yes)
			)
		)
		(property "Val" "220R"
			(at 264.16 227.33 0)
			(effects
				(font
					(size 1.27 1.27)
					(thickness 0.15)
				)
				(justify left)
			)
		)
		(property "Tolerance" "1%"
			(at 279.4 238.76 0)
			(effects
				(font
					(size 1.27 1.27)
				)
				(justify left bottom)
				(hide yes)
			)
		)
		(pin "1"
		)
		(pin "2"
		)
		(instances
			(project "OCuLink to 10GbE adapter"
				(path ""
					(reference "R41")
					(unit 1)
				)
			)
		)
	)
	(symbol
		(lib_id "antmicropower:GND")
		(at 167.64 243.84 0)
		(unit 1)
		(exclude_from_sim no)
		(in_bom yes)
		(on_board yes)
		(dnp no)
		(property "Reference" "#PWR084"
			(at 176.53 246.38 0)
			(effects
				(font
					(size 1.27 1.27)
					(thickness 0.15)
				)
				(justify left bottom)
				(hide yes)
			)
		)
		(property "Value" "GND"
			(at 167.64 247.65 0)
			(effects
				(font
					(size 1.27 1.27)
					(thickness 0.15)
				)
			)
		)
		(property "Footprint" ""
			(at 176.53 251.46 0)
			(effects
				(font
					(size 1.27 1.27)
					(thickness 0.15)
				)
				(justify left bottom)
				(hide yes)
			)
		)
		(property "Datasheet" ""
			(at 176.53 256.54 0)
			(effects
				(font
					(size 1.27 1.27)
					(thickness 0.15)
				)
				(justify left bottom)
				(hide yes)
			)
		)
		(property "Description" ""
			(at 167.64 243.84 0)
			(effects
				(font
					(size 1.27 1.27)
				)
				(hide yes)
			)
		)
		(property "Author" "Antmicro"
			(at 176.53 251.46 0)
			(effects
				(font
					(size 1.27 1.27)
					(thickness 0.15)
				)
				(justify left bottom)
				(hide yes)
			)
		)
		(property "License" "Apache-2.0"
			(at 176.53 254 0)
			(effects
				(font
					(size 1.27 1.27)
					(thickness 0.15)
				)
				(justify left bottom)
				(hide yes)
			)
		)
		(pin "1"
		)
		(instances
			(project "OCuLink to 10GbE adapter"
				(path ""
					(reference "#PWR084")
					(unit 1)
				)
			)
		)
	)
	(symbol
		(lib_id "antmicroResistors0402:R_220R_0402")
		(at 259.08 92.71 0)
		(unit 1)
		(exclude_from_sim no)
		(in_bom yes)
		(on_board yes)
		(dnp no)
		(property "Reference" "R38"
			(at 259.08 91.44 0)
			(effects
				(font
					(size 1.27 1.27)
					(thickness 0.15)
				)
				(justify right)
			)
		)
		(property "Value" "R_220R_0402"
			(at 279.4 105.41 0)
			(effects
				(font
					(size 1.27 1.27)
					(thickness 0.15)
				)
				(justify left bottom)
				(hide yes)
			)
		)
		(property "Footprint" "antmicro-footprints:R_0402_1005Metric"
			(at 279.4 107.95 0)
			(effects
				(font
					(size 1.27 1.27)
					(thickness 0.15)
				)
				(justify left bottom)
				(hide yes)
			)
		)
		(property "Datasheet" "https://www.bourns.com/docs/product-datasheets/cr.pdf"
			(at 279.4 110.49 0)
			(effects
				(font
					(size 1.27 1.27)
					(thickness 0.15)
				)
				(justify left bottom)
				(hide yes)
			)
		)
		(property "Description" "SMD Chip Resistor, 220 ohm, ± 1%, 62.5 mW, 0402 [1005 Metric], Thick Film, General Purpose"
			(at 259.08 92.71 0)
			(effects
				(font
					(size 1.27 1.27)
				)
				(hide yes)
			)
		)
		(property "MPN" "CR0402-FX-2200GLF"
			(at 279.4 113.03 0)
			(effects
				(font
					(size 1.27 1.27)
					(thickness 0.15)
				)
				(justify left bottom)
				(hide yes)
			)
		)
		(property "Manufacturer" "Bourns"
			(at 279.4 115.57 0)
			(effects
				(font
					(size 1.27 1.27)
					(thickness 0.15)
				)
				(justify left bottom)
				(hide yes)
			)
		)
		(property "License" "Apache-2.0"
			(at 279.4 118.11 0)
			(effects
				(font
					(size 1.27 1.27)
					(thickness 0.15)
				)
				(justify left bottom)
				(hide yes)
			)
		)
		(property "Author" "Antmicro"
			(at 279.4 120.65 0)
			(effects
				(font
					(size 1.27 1.27)
					(thickness 0.15)
				)
				(justify left bottom)
				(hide yes)
			)
		)
		(property "Val" "220R"
			(at 264.16 91.44 0)
			(effects
				(font
					(size 1.27 1.27)
					(thickness 0.15)
				)
				(justify left)
			)
		)
		(property "Tolerance" "1%"
			(at 279.4 102.87 0)
			(effects
				(font
					(size 1.27 1.27)
				)
				(justify left bottom)
				(hide yes)
			)
		)
		(pin "1"
		)
		(pin "2"
		)
		(instances
			(project "OCuLink to 10GbE adapter"
				(path ""
					(reference "R38")
					(unit 1)
				)
			)
		)
	)
)
